FILE_TYPE = MACRO_DRAWING;
SET COLOR_WIRE YELLOW;
SET COLOR_PROP ORANGE;
SET COLOR_DOT WHITE;
SET COLOR_ARC YELLOW;
SET COLOR_BODY GREEN;
SET COLOR_NOTE PURPLE;
SET PROP_DISPLAY VALUE;
SET PAGE_NUMBER P50;
FORCEADD GENOA_SP5..13
(-4750 5050);
FORCEPROP 1 LAST LOCATION U26
J 0
(-5845 6306);
DISPLAY 0.489362 (-5845 6306);
PAINT SKYBLUE (-5845 6306);
FORCEPROP 0 LAST $SEC 13
J 0
(-5825 6350);
DISPLAY 0.680851 (-5825 6350);
PAINT MONO (-5825 6350);
DISPLAY INVISIBLE (-5825 6350);
FORCEPROP 0 LAST CDS_SEC 13
J 0
(-5850 6275);
DISPLAY 1.021277 (-5850 6275);
DISPLAY INVISIBLE (-5850 6275);
FORCEPROP 0 LASTPIN (-6000 5750) $PN AE23
J 2
(-6010 5760);
DISPLAY 0.489362 (-6010 5760);
PAINT MONO (-6010 5760);
FORCEPROP 0 LASTPIN (-6000 5650) $PN AC23
J 2
(-6010 5660);
DISPLAY 0.489362 (-6010 5660);
PAINT MONO (-6010 5660);
FORCEPROP 0 LASTPIN (-6000 5550) $PN AG23
J 2
(-6010 5560);
DISPLAY 0.489362 (-6010 5560);
PAINT MONO (-6010 5560);
FORCEPROP 0 LASTPIN (-6000 5450) $PN AE26
J 2
(-6010 5460);
DISPLAY 0.489362 (-6010 5460);
PAINT MONO (-6010 5460);
FORCEPROP 0 LASTPIN (-6000 5350) $PN AC26
J 2
(-6010 5360);
DISPLAY 0.489362 (-6010 5360);
PAINT MONO (-6010 5360);
FORCEPROP 0 LASTPIN (-6000 5250) $PN AG26
J 2
(-6010 5260);
DISPLAY 0.489362 (-6010 5260);
PAINT MONO (-6010 5260);
FORCEPROP 0 LASTPIN (-6000 5150) $PN AE29
J 2
(-6010 5160);
DISPLAY 0.489362 (-6010 5160);
PAINT MONO (-6010 5160);
FORCEPROP 0 LASTPIN (-6000 5050) $PN AC29
J 2
(-6010 5060);
DISPLAY 0.489362 (-6010 5060);
PAINT MONO (-6010 5060);
FORCEPROP 0 LASTPIN (-6000 4950) $PN AG29
J 2
(-6010 4960);
DISPLAY 0.489362 (-6010 4960);
PAINT MONO (-6010 4960);
FORCEPROP 0 LASTPIN (-6000 4850) $PN AE32
J 2
(-6010 4860);
DISPLAY 0.489362 (-6010 4860);
PAINT MONO (-6010 4860);
FORCEPROP 0 LASTPIN (-6000 4750) $PN AC32
J 2
(-6010 4760);
DISPLAY 0.489362 (-6010 4760);
PAINT MONO (-6010 4760);
FORCEPROP 0 LASTPIN (-6000 4650) $PN AA32
J 2
(-6010 4660);
DISPLAY 0.489362 (-6010 4660);
PAINT MONO (-6010 4660);
FORCEPROP 0 LASTPIN (-6000 4550) $PN AG32
J 2
(-6010 4560);
DISPLAY 0.489362 (-6010 4560);
PAINT MONO (-6010 4560);
FORCEPROP 0 LASTPIN (-6000 4450) $PN AB35
J 2
(-6010 4460);
DISPLAY 0.489362 (-6010 4460);
PAINT MONO (-6010 4460);
FORCEPROP 0 LASTPIN (-6000 4350) $PN AD35
J 2
(-6010 4360);
DISPLAY 0.489362 (-6010 4360);
PAINT MONO (-6010 4360);
FORCEPROP 0 LASTPIN (-6000 4250) $PN AF35
J 2
(-6010 4260);
DISPLAY 0.489362 (-6010 4260);
PAINT MONO (-6010 4260);
FORCEPROP 0 LASTPIN (-6000 5800) $PN AE24
J 2
(-6010 5810);
DISPLAY 0.489362 (-6010 5810);
PAINT MONO (-6010 5810);
FORCEPROP 0 LASTPIN (-6000 5700) $PN AC24
J 2
(-6010 5710);
DISPLAY 0.489362 (-6010 5710);
PAINT MONO (-6010 5710);
FORCEPROP 0 LASTPIN (-6000 5600) $PN AG24
J 2
(-6010 5610);
DISPLAY 0.489362 (-6010 5610);
PAINT MONO (-6010 5610);
FORCEPROP 0 LASTPIN (-6000 5500) $PN AE27
J 2
(-6010 5510);
DISPLAY 0.489362 (-6010 5510);
PAINT MONO (-6010 5510);
FORCEPROP 0 LASTPIN (-6000 5400) $PN AC27
J 2
(-6010 5410);
DISPLAY 0.489362 (-6010 5410);
PAINT MONO (-6010 5410);
FORCEPROP 0 LASTPIN (-6000 5300) $PN AG27
J 2
(-6010 5310);
DISPLAY 0.489362 (-6010 5310);
PAINT MONO (-6010 5310);
FORCEPROP 0 LASTPIN (-6000 5200) $PN AE30
J 2
(-6010 5210);
DISPLAY 0.489362 (-6010 5210);
PAINT MONO (-6010 5210);
FORCEPROP 0 LASTPIN (-6000 5100) $PN AC30
J 2
(-6010 5110);
DISPLAY 0.489362 (-6010 5110);
PAINT MONO (-6010 5110);
FORCEPROP 0 LASTPIN (-6000 5000) $PN AG30
J 2
(-6010 5010);
DISPLAY 0.489362 (-6010 5010);
PAINT MONO (-6010 5010);
FORCEPROP 0 LASTPIN (-6000 4900) $PN AE33
J 2
(-6010 4910);
DISPLAY 0.489362 (-6010 4910);
PAINT MONO (-6010 4910);
FORCEPROP 0 LASTPIN (-6000 4800) $PN AC33
J 2
(-6010 4810);
DISPLAY 0.489362 (-6010 4810);
PAINT MONO (-6010 4810);
FORCEPROP 0 LASTPIN (-6000 4700) $PN AA33
J 2
(-6010 4710);
DISPLAY 0.489362 (-6010 4710);
PAINT MONO (-6010 4710);
FORCEPROP 0 LASTPIN (-6000 4600) $PN AG33
J 2
(-6010 4610);
DISPLAY 0.489362 (-6010 4610);
PAINT MONO (-6010 4610);
FORCEPROP 0 LASTPIN (-6000 4500) $PN AB36
J 2
(-6010 4510);
DISPLAY 0.489362 (-6010 4510);
PAINT MONO (-6010 4510);
FORCEPROP 0 LASTPIN (-6000 4400) $PN AD36
J 2
(-6010 4410);
DISPLAY 0.489362 (-6010 4410);
PAINT MONO (-6010 4410);
FORCEPROP 0 LASTPIN (-6000 4300) $PN AF36
J 2
(-6010 4310);
DISPLAY 0.489362 (-6010 4310);
PAINT MONO (-6010 4310);
FORCEPROP 0 LASTPIN (-3500 5750) $PN N24
J 0
(-3490 5760);
DISPLAY 0.489362 (-3490 5760);
PAINT MONO (-3490 5760);
FORCEPROP 0 LASTPIN (-3500 5650) $PN J24
J 0
(-3490 5660);
DISPLAY 0.489362 (-3490 5660);
PAINT MONO (-3490 5660);
FORCEPROP 0 LASTPIN (-3500 5550) $PN G24
J 0
(-3490 5560);
DISPLAY 0.489362 (-3490 5560);
PAINT MONO (-3490 5560);
FORCEPROP 0 LASTPIN (-3500 5450) $PN L24
J 0
(-3490 5460);
DISPLAY 0.489362 (-3490 5460);
PAINT MONO (-3490 5460);
FORCEPROP 0 LASTPIN (-3500 5350) $PN J27
J 0
(-3490 5360);
DISPLAY 0.489362 (-3490 5360);
PAINT MONO (-3490 5360);
FORCEPROP 0 LASTPIN (-3500 5250) $PN G27
J 0
(-3490 5260);
DISPLAY 0.489362 (-3490 5260);
PAINT MONO (-3490 5260);
FORCEPROP 0 LASTPIN (-3500 5150) $PN L27
J 0
(-3490 5160);
DISPLAY 0.489362 (-3490 5160);
PAINT MONO (-3490 5160);
FORCEPROP 0 LASTPIN (-3500 5050) $PN J30
J 0
(-3490 5060);
DISPLAY 0.489362 (-3490 5060);
PAINT MONO (-3490 5060);
FORCEPROP 0 LASTPIN (-3500 4950) $PN G30
J 0
(-3490 4960);
DISPLAY 0.489362 (-3490 4960);
PAINT MONO (-3490 4960);
FORCEPROP 0 LASTPIN (-3500 4850) $PN L30
J 0
(-3490 4860);
DISPLAY 0.489362 (-3490 4860);
PAINT MONO (-3490 4860);
FORCEPROP 0 LASTPIN (-3500 4750) $PN J33
J 0
(-3490 4760);
DISPLAY 0.489362 (-3490 4760);
PAINT MONO (-3490 4760);
FORCEPROP 0 LASTPIN (-3500 4650) $PN G33
J 0
(-3490 4660);
DISPLAY 0.489362 (-3490 4660);
PAINT MONO (-3490 4660);
FORCEPROP 0 LASTPIN (-3500 4550) $PN L33
J 0
(-3490 4560);
DISPLAY 0.489362 (-3490 4560);
PAINT MONO (-3490 4560);
FORCEPROP 0 LASTPIN (-3500 4450) $PN H36
J 0
(-3490 4460);
DISPLAY 0.489362 (-3490 4460);
PAINT MONO (-3490 4460);
FORCEPROP 0 LASTPIN (-3500 4350) $PN K36
J 0
(-3490 4360);
DISPLAY 0.489362 (-3490 4360);
PAINT MONO (-3490 4360);
FORCEPROP 0 LASTPIN (-3500 4250) $PN M36
J 0
(-3490 4260);
DISPLAY 0.489362 (-3490 4260);
PAINT MONO (-3490 4260);
FORCEPROP 0 LASTPIN (-3500 5800) $PN N23
J 0
(-3490 5810);
DISPLAY 0.489362 (-3490 5810);
PAINT MONO (-3490 5810);
FORCEPROP 0 LASTPIN (-3500 5700) $PN J23
J 0
(-3490 5710);
DISPLAY 0.489362 (-3490 5710);
PAINT MONO (-3490 5710);
FORCEPROP 0 LASTPIN (-3500 5600) $PN G23
J 0
(-3490 5610);
DISPLAY 0.489362 (-3490 5610);
PAINT MONO (-3490 5610);
FORCEPROP 0 LASTPIN (-3500 5500) $PN L23
J 0
(-3490 5510);
DISPLAY 0.489362 (-3490 5510);
PAINT MONO (-3490 5510);
FORCEPROP 0 LASTPIN (-3500 5400) $PN J26
J 0
(-3490 5410);
DISPLAY 0.489362 (-3490 5410);
PAINT MONO (-3490 5410);
FORCEPROP 0 LASTPIN (-3500 5300) $PN G26
J 0
(-3490 5310);
DISPLAY 0.489362 (-3490 5310);
PAINT MONO (-3490 5310);
FORCEPROP 0 LASTPIN (-3500 5200) $PN L26
J 0
(-3490 5210);
DISPLAY 0.489362 (-3490 5210);
PAINT MONO (-3490 5210);
FORCEPROP 0 LASTPIN (-3500 5100) $PN J29
J 0
(-3490 5110);
DISPLAY 0.489362 (-3490 5110);
PAINT MONO (-3490 5110);
FORCEPROP 0 LASTPIN (-3500 5000) $PN G29
J 0
(-3490 5010);
DISPLAY 0.489362 (-3490 5010);
PAINT MONO (-3490 5010);
FORCEPROP 0 LASTPIN (-3500 4900) $PN L29
J 0
(-3490 4910);
DISPLAY 0.489362 (-3490 4910);
PAINT MONO (-3490 4910);
FORCEPROP 0 LASTPIN (-3500 4800) $PN J32
J 0
(-3490 4810);
DISPLAY 0.489362 (-3490 4810);
PAINT MONO (-3490 4810);
FORCEPROP 0 LASTPIN (-3500 4700) $PN G32
J 0
(-3490 4710);
DISPLAY 0.489362 (-3490 4710);
PAINT MONO (-3490 4710);
FORCEPROP 0 LASTPIN (-3500 4600) $PN L32
J 0
(-3490 4610);
DISPLAY 0.489362 (-3490 4610);
PAINT MONO (-3490 4610);
FORCEPROP 0 LASTPIN (-3500 4500) $PN H35
J 0
(-3490 4510);
DISPLAY 0.489362 (-3490 4510);
PAINT MONO (-3490 4510);
FORCEPROP 0 LASTPIN (-3500 4400) $PN K35
J 0
(-3490 4410);
DISPLAY 0.489362 (-3490 4410);
PAINT MONO (-3490 4410);
FORCEPROP 0 LASTPIN (-3500 4300) $PN M35
J 0
(-3490 4310);
DISPLAY 0.489362 (-3490 4310);
PAINT MONO (-3490 4310);
FORCEPROP 2 LAST PART_TYPE SMLF
J 0
(-5850 6225);
DISPLAY 1.021277 (-5850 6225);
FORCEPROP 1 LAST MATERIAL IO
J 0
(-5845 6032);
DISPLAY 0.489362 (-5845 6032);
PAINT SKYBLUE (-5845 6032);
FORCEPROP 2 LAST VALUE SOCKET6096_13568-001
J 0
(-5850 6125);
DISPLAY 0.489362 (-5850 6125);
PAINT SKYBLUE (-5850 6125);
FORCEPROP 2 LAST CDS_LIB pure_quanta
J 0
(-4750 5050);
DISPLAY INVISIBLE (-4750 5050);
FORCEPROP 1 LAST NEEDS_NO_SIZE TRUE
J 0
(-4750 5050);
DISPLAY 0.723404 (-4750 5050);
PAINT GREEN (-4750 5050);
DISPLAY INVISIBLE (-4750 5050);
FORCEPROP 1 LAST CDS_LMAN_SYM_OUTLINE -1100,950,1100,-950
J 0
(-4750 5050);
DISPLAY 0.468085 (-4750 5050);
PAINT GREEN (-4750 5050);
DISPLAY INVISIBLE (-4750 5050);
FORCEPROP 1 LAST PATH I143
J 0
(-4750 5050);
DISPLAY 0.723404 (-4750 5050);
PAINT GREEN (-4750 5050);
DISPLAY INVISIBLE (-4750 5050);
FORCEPROP 1 LAST PART_NUMBER DGA^6000030
J 0
(-5845 6159);
DISPLAY 0.489362 (-5845 6159);
PAINT SKYBLUE (-5845 6159);
DISPLAY INVISIBLE (-5845 6159);
FORCEADD GENOA_SP5..14
(-4725 2375);
FORCEPROP 1 LAST LOCATION U26
J 0
(-5820 3631);
DISPLAY 0.489362 (-5820 3631);
PAINT SKYBLUE (-5820 3631);
FORCEPROP 0 LAST $SEC 14
J 0
(-5800 3675);
DISPLAY 0.680851 (-5800 3675);
PAINT MONO (-5800 3675);
DISPLAY INVISIBLE (-5800 3675);
FORCEPROP 0 LAST CDS_SEC 14
J 0
(-5825 3600);
DISPLAY 1.021277 (-5825 3600);
DISPLAY INVISIBLE (-5825 3600);
FORCEPROP 0 LASTPIN (-5975 3075) $PN AL23
J 2
(-5985 3085);
DISPLAY 0.489362 (-5985 3085);
PAINT MONO (-5985 3085);
FORCEPROP 0 LASTPIN (-5975 2975) $PN AJ23
J 2
(-5985 2985);
DISPLAY 0.489362 (-5985 2985);
PAINT MONO (-5985 2985);
FORCEPROP 0 LASTPIN (-5975 2875) $PN AN23
J 2
(-5985 2885);
DISPLAY 0.489362 (-5985 2885);
PAINT MONO (-5985 2885);
FORCEPROP 0 LASTPIN (-5975 2775) $PN AL26
J 2
(-5985 2785);
DISPLAY 0.489362 (-5985 2785);
PAINT MONO (-5985 2785);
FORCEPROP 0 LASTPIN (-5975 2675) $PN AJ26
J 2
(-5985 2685);
DISPLAY 0.489362 (-5985 2685);
PAINT MONO (-5985 2685);
FORCEPROP 0 LASTPIN (-5975 2575) $PN AN26
J 2
(-5985 2585);
DISPLAY 0.489362 (-5985 2585);
PAINT MONO (-5985 2585);
FORCEPROP 0 LASTPIN (-5975 2475) $PN AL29
J 2
(-5985 2485);
DISPLAY 0.489362 (-5985 2485);
PAINT MONO (-5985 2485);
FORCEPROP 0 LASTPIN (-5975 2375) $PN AJ29
J 2
(-5985 2385);
DISPLAY 0.489362 (-5985 2385);
PAINT MONO (-5985 2385);
FORCEPROP 0 LASTPIN (-5975 2275) $PN AN29
J 2
(-5985 2285);
DISPLAY 0.489362 (-5985 2285);
PAINT MONO (-5985 2285);
FORCEPROP 0 LASTPIN (-5975 2175) $PN AL32
J 2
(-5985 2185);
DISPLAY 0.489362 (-5985 2185);
PAINT MONO (-5985 2185);
FORCEPROP 0 LASTPIN (-5975 2075) $PN AJ32
J 2
(-5985 2085);
DISPLAY 0.489362 (-5985 2085);
PAINT MONO (-5985 2085);
FORCEPROP 0 LASTPIN (-5975 1975) $PN AN32
J 2
(-5985 1985);
DISPLAY 0.489362 (-5985 1985);
PAINT MONO (-5985 1985);
FORCEPROP 0 LASTPIN (-5975 1875) $PN AK35
J 2
(-5985 1885);
DISPLAY 0.489362 (-5985 1885);
PAINT MONO (-5985 1885);
FORCEPROP 0 LASTPIN (-5975 1775) $PN AH35
J 2
(-5985 1785);
DISPLAY 0.489362 (-5985 1785);
PAINT MONO (-5985 1785);
FORCEPROP 0 LASTPIN (-5975 1675) $PN AM35
J 2
(-5985 1685);
DISPLAY 0.489362 (-5985 1685);
PAINT MONO (-5985 1685);
FORCEPROP 0 LASTPIN (-5975 1575) $PN AP35
J 2
(-5985 1585);
DISPLAY 0.489362 (-5985 1585);
PAINT MONO (-5985 1585);
FORCEPROP 0 LASTPIN (-5975 3125) $PN AL24
J 2
(-5985 3135);
DISPLAY 0.489362 (-5985 3135);
PAINT MONO (-5985 3135);
FORCEPROP 0 LASTPIN (-5975 3025) $PN AJ24
J 2
(-5985 3035);
DISPLAY 0.489362 (-5985 3035);
PAINT MONO (-5985 3035);
FORCEPROP 0 LASTPIN (-5975 2925) $PN AN24
J 2
(-5985 2935);
DISPLAY 0.489362 (-5985 2935);
PAINT MONO (-5985 2935);
FORCEPROP 0 LASTPIN (-5975 2825) $PN AL27
J 2
(-5985 2835);
DISPLAY 0.489362 (-5985 2835);
PAINT MONO (-5985 2835);
FORCEPROP 0 LASTPIN (-5975 2725) $PN AJ27
J 2
(-5985 2735);
DISPLAY 0.489362 (-5985 2735);
PAINT MONO (-5985 2735);
FORCEPROP 0 LASTPIN (-5975 2625) $PN AN27
J 2
(-5985 2635);
DISPLAY 0.489362 (-5985 2635);
PAINT MONO (-5985 2635);
FORCEPROP 0 LASTPIN (-5975 2525) $PN AL30
J 2
(-5985 2535);
DISPLAY 0.489362 (-5985 2535);
PAINT MONO (-5985 2535);
FORCEPROP 0 LASTPIN (-5975 2425) $PN AJ30
J 2
(-5985 2435);
DISPLAY 0.489362 (-5985 2435);
PAINT MONO (-5985 2435);
FORCEPROP 0 LASTPIN (-5975 2325) $PN AN30
J 2
(-5985 2335);
DISPLAY 0.489362 (-5985 2335);
PAINT MONO (-5985 2335);
FORCEPROP 0 LASTPIN (-5975 2225) $PN AL33
J 2
(-5985 2235);
DISPLAY 0.489362 (-5985 2235);
PAINT MONO (-5985 2235);
FORCEPROP 0 LASTPIN (-5975 2125) $PN AJ33
J 2
(-5985 2135);
DISPLAY 0.489362 (-5985 2135);
PAINT MONO (-5985 2135);
FORCEPROP 0 LASTPIN (-5975 2025) $PN AN33
J 2
(-5985 2035);
DISPLAY 0.489362 (-5985 2035);
PAINT MONO (-5985 2035);
FORCEPROP 0 LASTPIN (-5975 1925) $PN AK36
J 2
(-5985 1935);
DISPLAY 0.489362 (-5985 1935);
PAINT MONO (-5985 1935);
FORCEPROP 0 LASTPIN (-5975 1825) $PN AH36
J 2
(-5985 1835);
DISPLAY 0.489362 (-5985 1835);
PAINT MONO (-5985 1835);
FORCEPROP 0 LASTPIN (-5975 1725) $PN AM36
J 2
(-5985 1735);
DISPLAY 0.489362 (-5985 1735);
PAINT MONO (-5985 1735);
FORCEPROP 0 LASTPIN (-5975 1625) $PN AP36
J 2
(-5985 1635);
DISPLAY 0.489362 (-5985 1635);
PAINT MONO (-5985 1635);
FORCEPROP 0 LASTPIN (-3475 3075) $PN U24
J 0
(-3465 3085);
DISPLAY 0.489362 (-3465 3085);
PAINT MONO (-3465 3085);
FORCEPROP 0 LASTPIN (-3475 2975) $PN R24
J 0
(-3465 2985);
DISPLAY 0.489362 (-3465 2985);
PAINT MONO (-3465 2985);
FORCEPROP 0 LASTPIN (-3475 2875) $PN W24
J 0
(-3465 2885);
DISPLAY 0.489362 (-3465 2885);
PAINT MONO (-3465 2885);
FORCEPROP 0 LASTPIN (-3475 2775) $PN U27
J 0
(-3465 2785);
DISPLAY 0.489362 (-3465 2785);
PAINT MONO (-3465 2785);
FORCEPROP 0 LASTPIN (-3475 2675) $PN R27
J 0
(-3465 2685);
DISPLAY 0.489362 (-3465 2685);
PAINT MONO (-3465 2685);
FORCEPROP 0 LASTPIN (-3475 2575) $PN N27
J 0
(-3465 2585);
DISPLAY 0.489362 (-3465 2585);
PAINT MONO (-3465 2585);
FORCEPROP 0 LASTPIN (-3475 2475) $PN W27
J 0
(-3465 2485);
DISPLAY 0.489362 (-3465 2485);
PAINT MONO (-3465 2485);
FORCEPROP 0 LASTPIN (-3475 2375) $PN R30
J 0
(-3465 2385);
DISPLAY 0.489362 (-3465 2385);
PAINT MONO (-3465 2385);
FORCEPROP 0 LASTPIN (-3475 2275) $PN N30
J 0
(-3465 2285);
DISPLAY 0.489362 (-3465 2285);
PAINT MONO (-3465 2285);
FORCEPROP 0 LASTPIN (-3475 2175) $PN U30
J 0
(-3465 2185);
DISPLAY 0.489362 (-3465 2185);
PAINT MONO (-3465 2185);
FORCEPROP 0 LASTPIN (-3475 2075) $PN R33
J 0
(-3465 2085);
DISPLAY 0.489362 (-3465 2085);
PAINT MONO (-3465 2085);
FORCEPROP 0 LASTPIN (-3475 1975) $PN N33
J 0
(-3465 1985);
DISPLAY 0.489362 (-3465 1985);
PAINT MONO (-3465 1985);
FORCEPROP 0 LASTPIN (-3475 1875) $PN U33
J 0
(-3465 1885);
DISPLAY 0.489362 (-3465 1885);
PAINT MONO (-3465 1885);
FORCEPROP 0 LASTPIN (-3475 1775) $PN P36
J 0
(-3465 1785);
DISPLAY 0.489362 (-3465 1785);
PAINT MONO (-3465 1785);
FORCEPROP 0 LASTPIN (-3475 1675) $PN T36
J 0
(-3465 1685);
DISPLAY 0.489362 (-3465 1685);
PAINT MONO (-3465 1685);
FORCEPROP 0 LASTPIN (-3475 1575) $PN V36
J 0
(-3465 1585);
DISPLAY 0.489362 (-3465 1585);
PAINT MONO (-3465 1585);
FORCEPROP 0 LASTPIN (-3475 3125) $PN U23
J 0
(-3465 3135);
DISPLAY 0.489362 (-3465 3135);
PAINT MONO (-3465 3135);
FORCEPROP 0 LASTPIN (-3475 3025) $PN R23
J 0
(-3465 3035);
DISPLAY 0.489362 (-3465 3035);
PAINT MONO (-3465 3035);
FORCEPROP 0 LASTPIN (-3475 2925) $PN W23
J 0
(-3465 2935);
DISPLAY 0.489362 (-3465 2935);
PAINT MONO (-3465 2935);
FORCEPROP 0 LASTPIN (-3475 2825) $PN U26
J 0
(-3465 2835);
DISPLAY 0.489362 (-3465 2835);
PAINT MONO (-3465 2835);
FORCEPROP 0 LASTPIN (-3475 2725) $PN R26
J 0
(-3465 2735);
DISPLAY 0.489362 (-3465 2735);
PAINT MONO (-3465 2735);
FORCEPROP 0 LASTPIN (-3475 2625) $PN N26
J 0
(-3465 2635);
DISPLAY 0.489362 (-3465 2635);
PAINT MONO (-3465 2635);
FORCEPROP 0 LASTPIN (-3475 2525) $PN W26
J 0
(-3465 2535);
DISPLAY 0.489362 (-3465 2535);
PAINT MONO (-3465 2535);
FORCEPROP 0 LASTPIN (-3475 2425) $PN R29
J 0
(-3465 2435);
DISPLAY 0.489362 (-3465 2435);
PAINT MONO (-3465 2435);
FORCEPROP 0 LASTPIN (-3475 2325) $PN N29
J 0
(-3465 2335);
DISPLAY 0.489362 (-3465 2335);
PAINT MONO (-3465 2335);
FORCEPROP 0 LASTPIN (-3475 2225) $PN U29
J 0
(-3465 2235);
DISPLAY 0.489362 (-3465 2235);
PAINT MONO (-3465 2235);
FORCEPROP 0 LASTPIN (-3475 2125) $PN R32
J 0
(-3465 2135);
DISPLAY 0.489362 (-3465 2135);
PAINT MONO (-3465 2135);
FORCEPROP 0 LASTPIN (-3475 2025) $PN N32
J 0
(-3465 2035);
DISPLAY 0.489362 (-3465 2035);
PAINT MONO (-3465 2035);
FORCEPROP 0 LASTPIN (-3475 1925) $PN U32
J 0
(-3465 1935);
DISPLAY 0.489362 (-3465 1935);
PAINT MONO (-3465 1935);
FORCEPROP 0 LASTPIN (-3475 1825) $PN P35
J 0
(-3465 1835);
DISPLAY 0.489362 (-3465 1835);
PAINT MONO (-3465 1835);
FORCEPROP 0 LASTPIN (-3475 1725) $PN T35
J 0
(-3465 1735);
DISPLAY 0.489362 (-3465 1735);
PAINT MONO (-3465 1735);
FORCEPROP 0 LASTPIN (-3475 1625) $PN V35
J 0
(-3465 1635);
DISPLAY 0.489362 (-3465 1635);
PAINT MONO (-3465 1635);
FORCEPROP 2 LAST PART_TYPE SMLF
J 0
(-5825 3550);
DISPLAY 1.021277 (-5825 3550);
FORCEPROP 1 LAST MATERIAL IO
J 0
(-5820 3357);
DISPLAY 0.489362 (-5820 3357);
PAINT SKYBLUE (-5820 3357);
FORCEPROP 2 LAST VALUE SOCKET6096_13568-001
J 0
(-5825 3450);
DISPLAY 0.489362 (-5825 3450);
PAINT SKYBLUE (-5825 3450);
FORCEPROP 2 LAST CDS_LIB pure_quanta
J 0
(-4725 2375);
DISPLAY INVISIBLE (-4725 2375);
FORCEPROP 1 LAST NEEDS_NO_SIZE TRUE
J 0
(-4725 2375);
DISPLAY 0.723404 (-4725 2375);
PAINT GREEN (-4725 2375);
DISPLAY INVISIBLE (-4725 2375);
FORCEPROP 1 LAST CDS_LMAN_SYM_OUTLINE -1100,950,1100,-950
J 0
(-4725 2375);
DISPLAY 0.468085 (-4725 2375);
PAINT GREEN (-4725 2375);
DISPLAY INVISIBLE (-4725 2375);
FORCEPROP 1 LAST PATH I144
J 0
(-4725 2375);
DISPLAY 0.723404 (-4725 2375);
PAINT GREEN (-4725 2375);
DISPLAY INVISIBLE (-4725 2375);
FORCEPROP 1 LAST PART_NUMBER DGA^6000030
J 0
(-5820 3484);
DISPLAY 0.489362 (-5820 3484);
PAINT SKYBLUE (-5820 3484);
DISPLAY INVISIBLE (-5820 3484);
FORCEADD OFFPAGE..2
(-1800 6025);
FORCEPROP 2 LAST $XR0 22 
J 0
(-1611 6025);
DISPLAY 0.638298 (-1611 6025);
PAINT MONO (-1611 6025);
FORCEPROP 2 LAST CDS_LIB standard
J 0
(-1800 6025);
DISPLAY INVISIBLE (-1800 6025);
FORCEPROP 1 LAST OFFPAGE TRUE
J 0
(-1475 5900);
DISPLAY 0.872340 (-1475 5900);
PAINT GREEN (-1475 5900);
DISPLAY INVISIBLE (-1475 5900);
FORCEPROP 1 LAST COMMENT_BODY TRUE
J 0
(-1845 5930);
DISPLAY 0.872340 (-1845 5930);
PAINT GREEN (-1845 5930);
DISPLAY INVISIBLE (-1845 5930);
FORCEPROP 2 LAST PATH I195
J 0
(-1600 6075);
DISPLAY 1.021277 (-1600 6075);
DISPLAY INVISIBLE (-1600 6075);
FORCEADD TAP..6
R 2
(-3075 5800);
FORCEPROP 3 LASTPIN (-3125 5800) SIG_NAME GMI_CPU1_G2_CPU0_G0_TX_DP<15>
J 0
(-3115 5810);
DISPLAY 0.659574 (-3115 5810);
PAINT MONO (-3115 5810);
DISPLAY INVISIBLE (-3115 5810);
FORCEPROP 1 LASTPIN (-3125 5800) BN 15
J 2
(-3073 5808);
DISPLAY 0.489362 (-3073 5808);
PAINT MONO (-3073 5808);
FORCEPROP 2 LAST BOM_COST IO_SLOT
J 0
(-3575 5900);
DISPLAY 0.829787 (-3575 5900);
DISPLAY INVISIBLE (-3575 5900);
FORCEPROP 2 LAST CDS_LIB mstr_standard
J 0
(-3075 5800);
DISPLAY INVISIBLE (-3075 5800);
FORCEPROP 2 LAST ROOM RISER1
J 0
(-3575 5850);
DISPLAY 0.829787 (-3575 5850);
PAINT RED (-3575 5850);
DISPLAY INVISIBLE (-3575 5850);
FORCEPROP 1 LAST BODY_TYPE PLUMBING
J 2
(-3075 5750);
DISPLAY 0.702128 (-3075 5750);
PAINT GREEN (-3075 5750);
DISPLAY INVISIBLE (-3075 5750);
FORCEPROP 1 LAST HDL_TAP TRUE
J 2
(-3400 5675);
DISPLAY 0.702128 (-3400 5675);
PAINT GREEN (-3400 5675);
DISPLAY INVISIBLE (-3400 5675);
FORCEPROP 1 LAST PATH I198
J 2
(-3073 5800);
DISPLAY 0.872340 (-3073 5800);
PAINT GREEN (-3073 5800);
DISPLAY INVISIBLE (-3073 5800);
FORCEADD TAP..6
R 2
(-3075 5700);
FORCEPROP 3 LASTPIN (-3125 5700) SIG_NAME GMI_CPU1_G2_CPU0_G0_TX_DP<14>
J 0
(-3115 5710);
DISPLAY 0.659574 (-3115 5710);
PAINT MONO (-3115 5710);
DISPLAY INVISIBLE (-3115 5710);
FORCEPROP 1 LASTPIN (-3125 5700) BN 14
J 2
(-3073 5708);
DISPLAY 0.489362 (-3073 5708);
PAINT MONO (-3073 5708);
FORCEPROP 2 LAST BOM_COST IO_SLOT
J 0
(-3575 5800);
DISPLAY 0.829787 (-3575 5800);
DISPLAY INVISIBLE (-3575 5800);
FORCEPROP 2 LAST CDS_LIB mstr_standard
J 0
(-3075 5700);
DISPLAY INVISIBLE (-3075 5700);
FORCEPROP 2 LAST ROOM RISER1
J 0
(-3575 5750);
DISPLAY 0.829787 (-3575 5750);
PAINT RED (-3575 5750);
DISPLAY INVISIBLE (-3575 5750);
FORCEPROP 1 LAST BODY_TYPE PLUMBING
J 2
(-3075 5650);
DISPLAY 0.702128 (-3075 5650);
PAINT GREEN (-3075 5650);
DISPLAY INVISIBLE (-3075 5650);
FORCEPROP 1 LAST HDL_TAP TRUE
J 2
(-3400 5575);
DISPLAY 0.702128 (-3400 5575);
PAINT GREEN (-3400 5575);
DISPLAY INVISIBLE (-3400 5575);
FORCEPROP 1 LAST PATH I199
J 2
(-3073 5700);
DISPLAY 0.872340 (-3073 5700);
PAINT GREEN (-3073 5700);
DISPLAY INVISIBLE (-3073 5700);
FORCEADD TAP..6
R 2
(-3075 5400);
FORCEPROP 3 LASTPIN (-3125 5400) SIG_NAME GMI_CPU1_G2_CPU0_G0_TX_DP<11>
J 0
(-3115 5410);
DISPLAY 0.659574 (-3115 5410);
PAINT MONO (-3115 5410);
DISPLAY INVISIBLE (-3115 5410);
FORCEPROP 1 LASTPIN (-3125 5400) BN 11
J 2
(-3073 5408);
DISPLAY 0.489362 (-3073 5408);
PAINT MONO (-3073 5408);
FORCEPROP 2 LAST BOM_COST IO_SLOT
J 0
(-3575 5500);
DISPLAY 0.829787 (-3575 5500);
DISPLAY INVISIBLE (-3575 5500);
FORCEPROP 2 LAST CDS_LIB standard
J 0
(-3075 5400);
DISPLAY INVISIBLE (-3075 5400);
FORCEPROP 2 LAST ROOM RISER1
J 0
(-3575 5450);
DISPLAY 0.829787 (-3575 5450);
PAINT RED (-3575 5450);
DISPLAY INVISIBLE (-3575 5450);
FORCEPROP 1 LAST BODY_TYPE PLUMBING
J 2
(-3075 5350);
DISPLAY 0.702128 (-3075 5350);
PAINT GREEN (-3075 5350);
DISPLAY INVISIBLE (-3075 5350);
FORCEPROP 1 LAST HDL_TAP TRUE
J 2
(-3400 5275);
DISPLAY 0.702128 (-3400 5275);
PAINT GREEN (-3400 5275);
DISPLAY INVISIBLE (-3400 5275);
FORCEPROP 1 LAST PATH I202
J 2
(-3073 5400);
DISPLAY 0.872340 (-3073 5400);
PAINT GREEN (-3073 5400);
DISPLAY INVISIBLE (-3073 5400);
FORCEADD TAP..6
R 2
(-3075 5600);
FORCEPROP 3 LASTPIN (-3125 5600) SIG_NAME GMI_CPU1_G2_CPU0_G0_TX_DP<13>
J 0
(-3115 5610);
DISPLAY 0.659574 (-3115 5610);
PAINT MONO (-3115 5610);
DISPLAY INVISIBLE (-3115 5610);
FORCEPROP 1 LASTPIN (-3125 5600) BN 13
J 2
(-3073 5608);
DISPLAY 0.489362 (-3073 5608);
PAINT MONO (-3073 5608);
FORCEPROP 2 LAST BOM_COST IO_SLOT
J 0
(-3575 5700);
DISPLAY 0.829787 (-3575 5700);
DISPLAY INVISIBLE (-3575 5700);
FORCEPROP 2 LAST CDS_LIB standard
J 0
(-3075 5600);
DISPLAY INVISIBLE (-3075 5600);
FORCEPROP 2 LAST ROOM RISER1
J 0
(-3575 5650);
DISPLAY 0.829787 (-3575 5650);
PAINT RED (-3575 5650);
DISPLAY INVISIBLE (-3575 5650);
FORCEPROP 1 LAST BODY_TYPE PLUMBING
J 2
(-3075 5550);
DISPLAY 0.702128 (-3075 5550);
PAINT GREEN (-3075 5550);
DISPLAY INVISIBLE (-3075 5550);
FORCEPROP 1 LAST HDL_TAP TRUE
J 2
(-3400 5475);
DISPLAY 0.702128 (-3400 5475);
PAINT GREEN (-3400 5475);
DISPLAY INVISIBLE (-3400 5475);
FORCEPROP 1 LAST PATH I203
J 2
(-3073 5600);
DISPLAY 0.872340 (-3073 5600);
PAINT GREEN (-3073 5600);
DISPLAY INVISIBLE (-3073 5600);
FORCEADD TAP..6
R 2
(-3075 5500);
FORCEPROP 3 LASTPIN (-3125 5500) SIG_NAME GMI_CPU1_G2_CPU0_G0_TX_DP<12>
J 0
(-3115 5510);
DISPLAY 0.659574 (-3115 5510);
PAINT MONO (-3115 5510);
DISPLAY INVISIBLE (-3115 5510);
FORCEPROP 1 LASTPIN (-3125 5500) BN 12
J 2
(-3073 5508);
DISPLAY 0.489362 (-3073 5508);
PAINT MONO (-3073 5508);
FORCEPROP 2 LAST BOM_COST IO_SLOT
J 0
(-3575 5600);
DISPLAY 0.829787 (-3575 5600);
DISPLAY INVISIBLE (-3575 5600);
FORCEPROP 2 LAST CDS_LIB standard
J 0
(-3075 5500);
DISPLAY INVISIBLE (-3075 5500);
FORCEPROP 2 LAST ROOM RISER1
J 0
(-3575 5550);
DISPLAY 0.829787 (-3575 5550);
PAINT RED (-3575 5550);
DISPLAY INVISIBLE (-3575 5550);
FORCEPROP 1 LAST BODY_TYPE PLUMBING
J 2
(-3075 5450);
DISPLAY 0.702128 (-3075 5450);
PAINT GREEN (-3075 5450);
DISPLAY INVISIBLE (-3075 5450);
FORCEPROP 1 LAST HDL_TAP TRUE
J 2
(-3400 5375);
DISPLAY 0.702128 (-3400 5375);
PAINT GREEN (-3400 5375);
DISPLAY INVISIBLE (-3400 5375);
FORCEPROP 1 LAST PATH I204
J 2
(-3073 5500);
DISPLAY 0.872340 (-3073 5500);
PAINT GREEN (-3073 5500);
DISPLAY INVISIBLE (-3073 5500);
FORCEADD TAP..6
R 2
(-3075 5200);
FORCEPROP 3 LASTPIN (-3125 5200) SIG_NAME GMI_CPU1_G2_CPU0_G0_TX_DP<9>
J 0
(-3115 5210);
DISPLAY 0.659574 (-3115 5210);
PAINT MONO (-3115 5210);
DISPLAY INVISIBLE (-3115 5210);
FORCEPROP 1 LASTPIN (-3125 5200) BN 9
J 2
(-3073 5208);
DISPLAY 0.489362 (-3073 5208);
PAINT MONO (-3073 5208);
FORCEPROP 2 LAST BOM_COST IO_SLOT
J 0
(-3575 5300);
DISPLAY 0.829787 (-3575 5300);
DISPLAY INVISIBLE (-3575 5300);
FORCEPROP 2 LAST CDS_LIB standard
J 0
(-3075 5200);
DISPLAY INVISIBLE (-3075 5200);
FORCEPROP 2 LAST ROOM RISER1
J 0
(-3575 5250);
DISPLAY 0.829787 (-3575 5250);
PAINT RED (-3575 5250);
DISPLAY INVISIBLE (-3575 5250);
FORCEPROP 1 LAST BODY_TYPE PLUMBING
J 2
(-3075 5150);
DISPLAY 0.702128 (-3075 5150);
PAINT GREEN (-3075 5150);
DISPLAY INVISIBLE (-3075 5150);
FORCEPROP 1 LAST HDL_TAP TRUE
J 2
(-3400 5075);
DISPLAY 0.702128 (-3400 5075);
PAINT GREEN (-3400 5075);
DISPLAY INVISIBLE (-3400 5075);
FORCEPROP 1 LAST PATH I208
J 2
(-3073 5200);
DISPLAY 0.872340 (-3073 5200);
PAINT GREEN (-3073 5200);
DISPLAY INVISIBLE (-3073 5200);
FORCEADD TAP..6
R 2
(-3075 5300);
FORCEPROP 3 LASTPIN (-3125 5300) SIG_NAME GMI_CPU1_G2_CPU0_G0_TX_DP<10>
J 0
(-3115 5310);
DISPLAY 0.659574 (-3115 5310);
PAINT MONO (-3115 5310);
DISPLAY INVISIBLE (-3115 5310);
FORCEPROP 1 LASTPIN (-3125 5300) BN 10
J 2
(-3073 5308);
DISPLAY 0.489362 (-3073 5308);
PAINT MONO (-3073 5308);
FORCEPROP 2 LAST BOM_COST IO_SLOT
J 0
(-3575 5400);
DISPLAY 0.829787 (-3575 5400);
DISPLAY INVISIBLE (-3575 5400);
FORCEPROP 2 LAST CDS_LIB standard
J 0
(-3075 5300);
DISPLAY INVISIBLE (-3075 5300);
FORCEPROP 2 LAST ROOM RISER1
J 0
(-3575 5350);
DISPLAY 0.829787 (-3575 5350);
PAINT RED (-3575 5350);
DISPLAY INVISIBLE (-3575 5350);
FORCEPROP 1 LAST BODY_TYPE PLUMBING
J 2
(-3075 5250);
DISPLAY 0.702128 (-3075 5250);
PAINT GREEN (-3075 5250);
DISPLAY INVISIBLE (-3075 5250);
FORCEPROP 1 LAST HDL_TAP TRUE
J 2
(-3400 5175);
DISPLAY 0.702128 (-3400 5175);
PAINT GREEN (-3400 5175);
DISPLAY INVISIBLE (-3400 5175);
FORCEPROP 1 LAST PATH I209
J 2
(-3073 5300);
DISPLAY 0.872340 (-3073 5300);
PAINT GREEN (-3073 5300);
DISPLAY INVISIBLE (-3073 5300);
FORCEADD TAP..6
R 2
(-3075 5100);
FORCEPROP 3 LASTPIN (-3125 5100) SIG_NAME GMI_CPU1_G2_CPU0_G0_TX_DP<8>
J 0
(-3115 5110);
DISPLAY 0.659574 (-3115 5110);
PAINT MONO (-3115 5110);
DISPLAY INVISIBLE (-3115 5110);
FORCEPROP 1 LASTPIN (-3125 5100) BN 8
J 2
(-3073 5108);
DISPLAY 0.489362 (-3073 5108);
PAINT MONO (-3073 5108);
FORCEPROP 2 LAST BOM_COST IO_SLOT
J 0
(-3575 5200);
DISPLAY 0.829787 (-3575 5200);
DISPLAY INVISIBLE (-3575 5200);
FORCEPROP 2 LAST CDS_LIB standard
J 0
(-3075 5100);
DISPLAY INVISIBLE (-3075 5100);
FORCEPROP 2 LAST ROOM RISER1
J 0
(-3575 5150);
DISPLAY 0.829787 (-3575 5150);
PAINT RED (-3575 5150);
DISPLAY INVISIBLE (-3575 5150);
FORCEPROP 1 LAST BODY_TYPE PLUMBING
J 2
(-3075 5050);
DISPLAY 0.702128 (-3075 5050);
PAINT GREEN (-3075 5050);
DISPLAY INVISIBLE (-3075 5050);
FORCEPROP 1 LAST HDL_TAP TRUE
J 2
(-3400 4975);
DISPLAY 0.702128 (-3400 4975);
PAINT GREEN (-3400 4975);
DISPLAY INVISIBLE (-3400 4975);
FORCEPROP 1 LAST PATH I212
J 2
(-3073 5100);
DISPLAY 0.872340 (-3073 5100);
PAINT GREEN (-3073 5100);
DISPLAY INVISIBLE (-3073 5100);
FORCEADD TAP..6
R 2
(-3075 5000);
FORCEPROP 3 LASTPIN (-3125 5000) SIG_NAME GMI_CPU1_G2_CPU0_G0_TX_DP<7>
J 0
(-3115 5010);
DISPLAY 0.659574 (-3115 5010);
PAINT MONO (-3115 5010);
DISPLAY INVISIBLE (-3115 5010);
FORCEPROP 1 LASTPIN (-3125 5000) BN 7
J 2
(-3073 5008);
DISPLAY 0.489362 (-3073 5008);
PAINT MONO (-3073 5008);
FORCEPROP 2 LAST BOM_COST IO_SLOT
J 0
(-3575 5100);
DISPLAY 0.829787 (-3575 5100);
DISPLAY INVISIBLE (-3575 5100);
FORCEPROP 2 LAST CDS_LIB standard
J 0
(-3075 5000);
DISPLAY INVISIBLE (-3075 5000);
FORCEPROP 2 LAST ROOM RISER1
J 0
(-3575 5050);
DISPLAY 0.829787 (-3575 5050);
PAINT RED (-3575 5050);
DISPLAY INVISIBLE (-3575 5050);
FORCEPROP 1 LAST BODY_TYPE PLUMBING
J 2
(-3075 4950);
DISPLAY 0.702128 (-3075 4950);
PAINT GREEN (-3075 4950);
DISPLAY INVISIBLE (-3075 4950);
FORCEPROP 1 LAST HDL_TAP TRUE
J 2
(-3400 4875);
DISPLAY 0.702128 (-3400 4875);
PAINT GREEN (-3400 4875);
DISPLAY INVISIBLE (-3400 4875);
FORCEPROP 1 LAST PATH I213
J 2
(-3073 5000);
DISPLAY 0.872340 (-3073 5000);
PAINT GREEN (-3073 5000);
DISPLAY INVISIBLE (-3073 5000);
FORCEADD TAP..6
R 2
(-3075 4900);
FORCEPROP 3 LASTPIN (-3125 4900) SIG_NAME GMI_CPU1_G2_CPU0_G0_TX_DP<6>
J 0
(-3115 4910);
DISPLAY 0.659574 (-3115 4910);
PAINT MONO (-3115 4910);
DISPLAY INVISIBLE (-3115 4910);
FORCEPROP 1 LASTPIN (-3125 4900) BN 6
J 2
(-3073 4908);
DISPLAY 0.489362 (-3073 4908);
PAINT MONO (-3073 4908);
FORCEPROP 2 LAST BOM_COST IO_SLOT
J 0
(-3575 5000);
DISPLAY 0.829787 (-3575 5000);
DISPLAY INVISIBLE (-3575 5000);
FORCEPROP 2 LAST CDS_LIB standard
J 0
(-3075 4900);
DISPLAY INVISIBLE (-3075 4900);
FORCEPROP 2 LAST ROOM RISER1
J 0
(-3575 4950);
DISPLAY 0.829787 (-3575 4950);
PAINT RED (-3575 4950);
DISPLAY INVISIBLE (-3575 4950);
FORCEPROP 1 LAST BODY_TYPE PLUMBING
J 2
(-3075 4850);
DISPLAY 0.702128 (-3075 4850);
PAINT GREEN (-3075 4850);
DISPLAY INVISIBLE (-3075 4850);
FORCEPROP 1 LAST HDL_TAP TRUE
J 2
(-3400 4775);
DISPLAY 0.702128 (-3400 4775);
PAINT GREEN (-3400 4775);
DISPLAY INVISIBLE (-3400 4775);
FORCEPROP 1 LAST PATH I214
J 2
(-3073 4900);
DISPLAY 0.872340 (-3073 4900);
PAINT GREEN (-3073 4900);
DISPLAY INVISIBLE (-3073 4900);
FORCEADD TAP..6
R 2
(-3075 4700);
FORCEPROP 3 LASTPIN (-3125 4700) SIG_NAME GMI_CPU1_G2_CPU0_G0_TX_DP<4>
J 0
(-3115 4710);
DISPLAY 0.659574 (-3115 4710);
PAINT MONO (-3115 4710);
DISPLAY INVISIBLE (-3115 4710);
FORCEPROP 1 LASTPIN (-3125 4700) BN 4
J 2
(-3073 4708);
DISPLAY 0.489362 (-3073 4708);
PAINT MONO (-3073 4708);
FORCEPROP 2 LAST BOM_COST IO_SLOT
J 0
(-3575 4800);
DISPLAY 0.829787 (-3575 4800);
DISPLAY INVISIBLE (-3575 4800);
FORCEPROP 2 LAST CDS_LIB standard
J 0
(-3075 4700);
DISPLAY INVISIBLE (-3075 4700);
FORCEPROP 2 LAST ROOM RISER1
J 0
(-3575 4750);
DISPLAY 0.829787 (-3575 4750);
PAINT RED (-3575 4750);
DISPLAY INVISIBLE (-3575 4750);
FORCEPROP 1 LAST BODY_TYPE PLUMBING
J 2
(-3075 4650);
DISPLAY 0.702128 (-3075 4650);
PAINT GREEN (-3075 4650);
DISPLAY INVISIBLE (-3075 4650);
FORCEPROP 1 LAST HDL_TAP TRUE
J 2
(-3400 4575);
DISPLAY 0.702128 (-3400 4575);
PAINT GREEN (-3400 4575);
DISPLAY INVISIBLE (-3400 4575);
FORCEPROP 1 LAST PATH I218
J 2
(-3073 4700);
DISPLAY 0.872340 (-3073 4700);
PAINT GREEN (-3073 4700);
DISPLAY INVISIBLE (-3073 4700);
FORCEADD TAP..6
R 2
(-3075 4800);
FORCEPROP 3 LASTPIN (-3125 4800) SIG_NAME GMI_CPU1_G2_CPU0_G0_TX_DP<5>
J 0
(-3115 4810);
DISPLAY 0.659574 (-3115 4810);
PAINT MONO (-3115 4810);
DISPLAY INVISIBLE (-3115 4810);
FORCEPROP 1 LASTPIN (-3125 4800) BN 5
J 2
(-3073 4808);
DISPLAY 0.489362 (-3073 4808);
PAINT MONO (-3073 4808);
FORCEPROP 2 LAST BOM_COST IO_SLOT
J 0
(-3575 4900);
DISPLAY 0.829787 (-3575 4900);
DISPLAY INVISIBLE (-3575 4900);
FORCEPROP 2 LAST CDS_LIB standard
J 0
(-3075 4800);
DISPLAY INVISIBLE (-3075 4800);
FORCEPROP 2 LAST ROOM RISER1
J 0
(-3575 4850);
DISPLAY 0.829787 (-3575 4850);
PAINT RED (-3575 4850);
DISPLAY INVISIBLE (-3575 4850);
FORCEPROP 1 LAST BODY_TYPE PLUMBING
J 2
(-3075 4750);
DISPLAY 0.702128 (-3075 4750);
PAINT GREEN (-3075 4750);
DISPLAY INVISIBLE (-3075 4750);
FORCEPROP 1 LAST HDL_TAP TRUE
J 2
(-3400 4675);
DISPLAY 0.702128 (-3400 4675);
PAINT GREEN (-3400 4675);
DISPLAY INVISIBLE (-3400 4675);
FORCEPROP 1 LAST PATH I219
J 2
(-3073 4800);
DISPLAY 0.872340 (-3073 4800);
PAINT GREEN (-3073 4800);
DISPLAY INVISIBLE (-3073 4800);
FORCEADD TAP..6
R 2
(-3075 4600);
FORCEPROP 3 LASTPIN (-3125 4600) SIG_NAME GMI_CPU1_G2_CPU0_G0_TX_DP<3>
J 0
(-3115 4610);
DISPLAY 0.659574 (-3115 4610);
PAINT MONO (-3115 4610);
DISPLAY INVISIBLE (-3115 4610);
FORCEPROP 1 LASTPIN (-3125 4600) BN 3
J 2
(-3073 4608);
DISPLAY 0.489362 (-3073 4608);
PAINT MONO (-3073 4608);
FORCEPROP 2 LAST BOM_COST IO_SLOT
J 0
(-3575 4700);
DISPLAY 0.829787 (-3575 4700);
DISPLAY INVISIBLE (-3575 4700);
FORCEPROP 2 LAST CDS_LIB standard
J 0
(-3075 4600);
DISPLAY INVISIBLE (-3075 4600);
FORCEPROP 2 LAST ROOM RISER1
J 0
(-3575 4650);
DISPLAY 0.829787 (-3575 4650);
PAINT RED (-3575 4650);
DISPLAY INVISIBLE (-3575 4650);
FORCEPROP 1 LAST BODY_TYPE PLUMBING
J 2
(-3075 4550);
DISPLAY 0.702128 (-3075 4550);
PAINT GREEN (-3075 4550);
DISPLAY INVISIBLE (-3075 4550);
FORCEPROP 1 LAST HDL_TAP TRUE
J 2
(-3400 4475);
DISPLAY 0.702128 (-3400 4475);
PAINT GREEN (-3400 4475);
DISPLAY INVISIBLE (-3400 4475);
FORCEPROP 1 LAST PATH I222
J 2
(-3073 4600);
DISPLAY 0.872340 (-3073 4600);
PAINT GREEN (-3073 4600);
DISPLAY INVISIBLE (-3073 4600);
FORCEADD TAP..6
R 2
(-3075 4500);
FORCEPROP 3 LASTPIN (-3125 4500) SIG_NAME GMI_CPU1_G2_CPU0_G0_TX_DP<2>
J 0
(-3115 4510);
DISPLAY 0.659574 (-3115 4510);
PAINT MONO (-3115 4510);
DISPLAY INVISIBLE (-3115 4510);
FORCEPROP 1 LASTPIN (-3125 4500) BN 2
J 2
(-3073 4508);
DISPLAY 0.489362 (-3073 4508);
PAINT MONO (-3073 4508);
FORCEPROP 2 LAST BOM_COST IO_SLOT
J 0
(-3575 4600);
DISPLAY 0.829787 (-3575 4600);
DISPLAY INVISIBLE (-3575 4600);
FORCEPROP 2 LAST CDS_LIB standard
J 0
(-3075 4500);
DISPLAY INVISIBLE (-3075 4500);
FORCEPROP 2 LAST ROOM RISER1
J 0
(-3575 4550);
DISPLAY 0.829787 (-3575 4550);
PAINT RED (-3575 4550);
DISPLAY INVISIBLE (-3575 4550);
FORCEPROP 1 LAST BODY_TYPE PLUMBING
J 2
(-3075 4450);
DISPLAY 0.702128 (-3075 4450);
PAINT GREEN (-3075 4450);
DISPLAY INVISIBLE (-3075 4450);
FORCEPROP 1 LAST HDL_TAP TRUE
J 2
(-3400 4375);
DISPLAY 0.702128 (-3400 4375);
PAINT GREEN (-3400 4375);
DISPLAY INVISIBLE (-3400 4375);
FORCEPROP 1 LAST PATH I223
J 2
(-3073 4500);
DISPLAY 0.872340 (-3073 4500);
PAINT GREEN (-3073 4500);
DISPLAY INVISIBLE (-3073 4500);
FORCEADD TAP..6
R 2
(-3075 4400);
FORCEPROP 3 LASTPIN (-3125 4400) SIG_NAME GMI_CPU1_G2_CPU0_G0_TX_DP<1>
J 0
(-3115 4410);
DISPLAY 0.659574 (-3115 4410);
PAINT MONO (-3115 4410);
DISPLAY INVISIBLE (-3115 4410);
FORCEPROP 1 LASTPIN (-3125 4400) BN 1
J 2
(-3073 4408);
DISPLAY 0.489362 (-3073 4408);
PAINT MONO (-3073 4408);
FORCEPROP 2 LAST BOM_COST IO_SLOT
J 0
(-3575 4500);
DISPLAY 0.829787 (-3575 4500);
DISPLAY INVISIBLE (-3575 4500);
FORCEPROP 2 LAST CDS_LIB standard
J 0
(-3075 4400);
DISPLAY INVISIBLE (-3075 4400);
FORCEPROP 2 LAST ROOM RISER1
J 0
(-3575 4450);
DISPLAY 0.829787 (-3575 4450);
PAINT RED (-3575 4450);
DISPLAY INVISIBLE (-3575 4450);
FORCEPROP 1 LAST BODY_TYPE PLUMBING
J 2
(-3075 4350);
DISPLAY 0.702128 (-3075 4350);
PAINT GREEN (-3075 4350);
DISPLAY INVISIBLE (-3075 4350);
FORCEPROP 1 LAST HDL_TAP TRUE
J 2
(-3400 4275);
DISPLAY 0.702128 (-3400 4275);
PAINT GREEN (-3400 4275);
DISPLAY INVISIBLE (-3400 4275);
FORCEPROP 1 LAST PATH I224
J 2
(-3073 4400);
DISPLAY 0.872340 (-3073 4400);
PAINT GREEN (-3073 4400);
DISPLAY INVISIBLE (-3073 4400);
FORCEADD TAP..6
R 2
(-3075 4300);
FORCEPROP 3 LASTPIN (-3125 4300) SIG_NAME GMI_CPU1_G2_CPU0_G0_TX_DP<0>
J 0
(-3115 4310);
DISPLAY 0.659574 (-3115 4310);
PAINT MONO (-3115 4310);
DISPLAY INVISIBLE (-3115 4310);
FORCEPROP 1 LASTPIN (-3125 4300) BN 0
J 2
(-3073 4308);
DISPLAY 0.489362 (-3073 4308);
PAINT MONO (-3073 4308);
FORCEPROP 2 LAST BOM_COST IO_SLOT
J 0
(-3575 4400);
DISPLAY 0.829787 (-3575 4400);
DISPLAY INVISIBLE (-3575 4400);
FORCEPROP 2 LAST CDS_LIB standard
J 0
(-3075 4300);
DISPLAY INVISIBLE (-3075 4300);
FORCEPROP 2 LAST ROOM RISER1
J 0
(-3575 4350);
DISPLAY 0.829787 (-3575 4350);
PAINT RED (-3575 4350);
DISPLAY INVISIBLE (-3575 4350);
FORCEPROP 1 LAST BODY_TYPE PLUMBING
J 2
(-3075 4250);
DISPLAY 0.702128 (-3075 4250);
PAINT GREEN (-3075 4250);
DISPLAY INVISIBLE (-3075 4250);
FORCEPROP 1 LAST HDL_TAP TRUE
J 2
(-3400 4175);
DISPLAY 0.702128 (-3400 4175);
PAINT GREEN (-3400 4175);
DISPLAY INVISIBLE (-3400 4175);
FORCEPROP 1 LAST PATH I225
J 2
(-3073 4300);
DISPLAY 0.872340 (-3073 4300);
PAINT GREEN (-3073 4300);
DISPLAY INVISIBLE (-3073 4300);
FORCEADD OFFPAGE..2
(-1775 3350);
FORCEPROP 2 LAST $XR0 22 
J 0
(-1586 3350);
DISPLAY 0.638298 (-1586 3350);
PAINT MONO (-1586 3350);
FORCEPROP 2 LAST CDS_LIB standard
J 0
(-1775 3350);
DISPLAY INVISIBLE (-1775 3350);
FORCEPROP 1 LAST OFFPAGE TRUE
J 0
(-1450 3225);
DISPLAY 0.872340 (-1450 3225);
PAINT GREEN (-1450 3225);
DISPLAY INVISIBLE (-1450 3225);
FORCEPROP 1 LAST COMMENT_BODY TRUE
J 0
(-1820 3255);
DISPLAY 0.872340 (-1820 3255);
PAINT GREEN (-1820 3255);
DISPLAY INVISIBLE (-1820 3255);
FORCEPROP 2 LAST PATH I228
J 0
(-1575 3400);
DISPLAY 1.021277 (-1575 3400);
DISPLAY INVISIBLE (-1575 3400);
FORCEADD TAP..6
R 2
(-3050 3125);
FORCEPROP 3 LASTPIN (-3100 3125) SIG_NAME GMI_CPU1_G3_CPU0_G1_TX_DP<15>
J 0
(-3090 3135);
DISPLAY 0.659574 (-3090 3135);
PAINT MONO (-3090 3135);
DISPLAY INVISIBLE (-3090 3135);
FORCEPROP 1 LASTPIN (-3100 3125) BN 15
J 2
(-3048 3133);
DISPLAY 0.489362 (-3048 3133);
PAINT MONO (-3048 3133);
FORCEPROP 2 LAST CDS_LIB mstr_standard
J 0
(-3050 3125);
DISPLAY INVISIBLE (-3050 3125);
FORCEPROP 2 LAST BOM_COST IO_SLOT
J 0
(-3550 3225);
DISPLAY 0.829787 (-3550 3225);
DISPLAY INVISIBLE (-3550 3225);
FORCEPROP 2 LAST ROOM RISER1
J 0
(-3550 3175);
DISPLAY 0.829787 (-3550 3175);
PAINT RED (-3550 3175);
DISPLAY INVISIBLE (-3550 3175);
FORCEPROP 1 LAST BODY_TYPE PLUMBING
J 2
(-3050 3075);
DISPLAY 0.702128 (-3050 3075);
PAINT GREEN (-3050 3075);
DISPLAY INVISIBLE (-3050 3075);
FORCEPROP 1 LAST HDL_TAP TRUE
J 2
(-3375 3000);
DISPLAY 0.702128 (-3375 3000);
PAINT GREEN (-3375 3000);
DISPLAY INVISIBLE (-3375 3000);
FORCEPROP 1 LAST PATH I241
J 2
(-3048 3125);
DISPLAY 0.872340 (-3048 3125);
PAINT GREEN (-3048 3125);
DISPLAY INVISIBLE (-3048 3125);
FORCEADD TAP..6
R 2
(-3050 2925);
FORCEPROP 3 LASTPIN (-3100 2925) SIG_NAME GMI_CPU1_G3_CPU0_G1_TX_DP<13>
J 0
(-3090 2935);
DISPLAY 0.659574 (-3090 2935);
PAINT MONO (-3090 2935);
DISPLAY INVISIBLE (-3090 2935);
FORCEPROP 1 LASTPIN (-3100 2925) BN 13
J 2
(-3048 2933);
DISPLAY 0.489362 (-3048 2933);
PAINT MONO (-3048 2933);
FORCEPROP 2 LAST CDS_LIB standard
J 0
(-3050 2925);
DISPLAY INVISIBLE (-3050 2925);
FORCEPROP 2 LAST BOM_COST IO_SLOT
J 0
(-3550 3025);
DISPLAY 0.829787 (-3550 3025);
DISPLAY INVISIBLE (-3550 3025);
FORCEPROP 2 LAST ROOM RISER1
J 0
(-3550 2975);
DISPLAY 0.829787 (-3550 2975);
PAINT RED (-3550 2975);
DISPLAY INVISIBLE (-3550 2975);
FORCEPROP 1 LAST BODY_TYPE PLUMBING
J 2
(-3050 2875);
DISPLAY 0.702128 (-3050 2875);
PAINT GREEN (-3050 2875);
DISPLAY INVISIBLE (-3050 2875);
FORCEPROP 1 LAST HDL_TAP TRUE
J 2
(-3375 2800);
DISPLAY 0.702128 (-3375 2800);
PAINT GREEN (-3375 2800);
DISPLAY INVISIBLE (-3375 2800);
FORCEPROP 1 LAST PATH I242
J 2
(-3048 2925);
DISPLAY 0.872340 (-3048 2925);
PAINT GREEN (-3048 2925);
DISPLAY INVISIBLE (-3048 2925);
FORCEADD TAP..6
R 2
(-3050 2825);
FORCEPROP 3 LASTPIN (-3100 2825) SIG_NAME GMI_CPU1_G3_CPU0_G1_TX_DP<12>
J 0
(-3090 2835);
DISPLAY 0.659574 (-3090 2835);
PAINT MONO (-3090 2835);
DISPLAY INVISIBLE (-3090 2835);
FORCEPROP 1 LASTPIN (-3100 2825) BN 12
J 2
(-3048 2833);
DISPLAY 0.489362 (-3048 2833);
PAINT MONO (-3048 2833);
FORCEPROP 2 LAST CDS_LIB standard
J 0
(-3050 2825);
DISPLAY INVISIBLE (-3050 2825);
FORCEPROP 2 LAST BOM_COST IO_SLOT
J 0
(-3550 2925);
DISPLAY 0.829787 (-3550 2925);
DISPLAY INVISIBLE (-3550 2925);
FORCEPROP 2 LAST ROOM RISER1
J 0
(-3550 2875);
DISPLAY 0.829787 (-3550 2875);
PAINT RED (-3550 2875);
DISPLAY INVISIBLE (-3550 2875);
FORCEPROP 1 LAST BODY_TYPE PLUMBING
J 2
(-3050 2775);
DISPLAY 0.702128 (-3050 2775);
PAINT GREEN (-3050 2775);
DISPLAY INVISIBLE (-3050 2775);
FORCEPROP 1 LAST HDL_TAP TRUE
J 2
(-3375 2700);
DISPLAY 0.702128 (-3375 2700);
PAINT GREEN (-3375 2700);
DISPLAY INVISIBLE (-3375 2700);
FORCEPROP 1 LAST PATH I243
J 2
(-3048 2825);
DISPLAY 0.872340 (-3048 2825);
PAINT GREEN (-3048 2825);
DISPLAY INVISIBLE (-3048 2825);
FORCEADD TAP..6
R 2
(-3050 3025);
FORCEPROP 3 LASTPIN (-3100 3025) SIG_NAME GMI_CPU1_G3_CPU0_G1_TX_DP<14>
J 0
(-3090 3035);
DISPLAY 0.659574 (-3090 3035);
PAINT MONO (-3090 3035);
DISPLAY INVISIBLE (-3090 3035);
FORCEPROP 1 LASTPIN (-3100 3025) BN 14
J 2
(-3048 3033);
DISPLAY 0.489362 (-3048 3033);
PAINT MONO (-3048 3033);
FORCEPROP 2 LAST CDS_LIB mstr_standard
J 0
(-3050 3025);
DISPLAY INVISIBLE (-3050 3025);
FORCEPROP 2 LAST BOM_COST IO_SLOT
J 0
(-3550 3125);
DISPLAY 0.829787 (-3550 3125);
DISPLAY INVISIBLE (-3550 3125);
FORCEPROP 2 LAST ROOM RISER1
J 0
(-3550 3075);
DISPLAY 0.829787 (-3550 3075);
PAINT RED (-3550 3075);
DISPLAY INVISIBLE (-3550 3075);
FORCEPROP 1 LAST BODY_TYPE PLUMBING
J 2
(-3050 2975);
DISPLAY 0.702128 (-3050 2975);
PAINT GREEN (-3050 2975);
DISPLAY INVISIBLE (-3050 2975);
FORCEPROP 1 LAST HDL_TAP TRUE
J 2
(-3375 2900);
DISPLAY 0.702128 (-3375 2900);
PAINT GREEN (-3375 2900);
DISPLAY INVISIBLE (-3375 2900);
FORCEPROP 1 LAST PATH I244
J 2
(-3048 3025);
DISPLAY 0.872340 (-3048 3025);
PAINT GREEN (-3048 3025);
DISPLAY INVISIBLE (-3048 3025);
FORCEADD TAP..6
R 2
(-3050 2725);
FORCEPROP 3 LASTPIN (-3100 2725) SIG_NAME GMI_CPU1_G3_CPU0_G1_TX_DP<11>
J 0
(-3090 2735);
DISPLAY 0.659574 (-3090 2735);
PAINT MONO (-3090 2735);
DISPLAY INVISIBLE (-3090 2735);
FORCEPROP 1 LASTPIN (-3100 2725) BN 11
J 2
(-3048 2733);
DISPLAY 0.489362 (-3048 2733);
PAINT MONO (-3048 2733);
FORCEPROP 2 LAST CDS_LIB standard
J 0
(-3050 2725);
DISPLAY INVISIBLE (-3050 2725);
FORCEPROP 2 LAST BOM_COST IO_SLOT
J 0
(-3550 2825);
DISPLAY 0.829787 (-3550 2825);
DISPLAY INVISIBLE (-3550 2825);
FORCEPROP 2 LAST ROOM RISER1
J 0
(-3550 2775);
DISPLAY 0.829787 (-3550 2775);
PAINT RED (-3550 2775);
DISPLAY INVISIBLE (-3550 2775);
FORCEPROP 1 LAST BODY_TYPE PLUMBING
J 2
(-3050 2675);
DISPLAY 0.702128 (-3050 2675);
PAINT GREEN (-3050 2675);
DISPLAY INVISIBLE (-3050 2675);
FORCEPROP 1 LAST HDL_TAP TRUE
J 2
(-3375 2600);
DISPLAY 0.702128 (-3375 2600);
PAINT GREEN (-3375 2600);
DISPLAY INVISIBLE (-3375 2600);
FORCEPROP 1 LAST PATH I245
J 2
(-3048 2725);
DISPLAY 0.872340 (-3048 2725);
PAINT GREEN (-3048 2725);
DISPLAY INVISIBLE (-3048 2725);
FORCEADD TAP..6
R 2
(-3050 2625);
FORCEPROP 3 LASTPIN (-3100 2625) SIG_NAME GMI_CPU1_G3_CPU0_G1_TX_DP<10>
J 0
(-3090 2635);
DISPLAY 0.659574 (-3090 2635);
PAINT MONO (-3090 2635);
DISPLAY INVISIBLE (-3090 2635);
FORCEPROP 1 LASTPIN (-3100 2625) BN 10
J 2
(-3048 2633);
DISPLAY 0.489362 (-3048 2633);
PAINT MONO (-3048 2633);
FORCEPROP 2 LAST CDS_LIB standard
J 0
(-3050 2625);
DISPLAY INVISIBLE (-3050 2625);
FORCEPROP 2 LAST BOM_COST IO_SLOT
J 0
(-3550 2725);
DISPLAY 0.829787 (-3550 2725);
DISPLAY INVISIBLE (-3550 2725);
FORCEPROP 2 LAST ROOM RISER1
J 0
(-3550 2675);
DISPLAY 0.829787 (-3550 2675);
PAINT RED (-3550 2675);
DISPLAY INVISIBLE (-3550 2675);
FORCEPROP 1 LAST BODY_TYPE PLUMBING
J 2
(-3050 2575);
DISPLAY 0.702128 (-3050 2575);
PAINT GREEN (-3050 2575);
DISPLAY INVISIBLE (-3050 2575);
FORCEPROP 1 LAST HDL_TAP TRUE
J 2
(-3375 2500);
DISPLAY 0.702128 (-3375 2500);
PAINT GREEN (-3375 2500);
DISPLAY INVISIBLE (-3375 2500);
FORCEPROP 1 LAST PATH I246
J 2
(-3048 2625);
DISPLAY 0.872340 (-3048 2625);
PAINT GREEN (-3048 2625);
DISPLAY INVISIBLE (-3048 2625);
FORCEADD TAP..6
R 2
(-3050 2425);
FORCEPROP 3 LASTPIN (-3100 2425) SIG_NAME GMI_CPU1_G3_CPU0_G1_TX_DP<8>
J 0
(-3090 2435);
DISPLAY 0.659574 (-3090 2435);
PAINT MONO (-3090 2435);
DISPLAY INVISIBLE (-3090 2435);
FORCEPROP 1 LASTPIN (-3100 2425) BN 8
J 2
(-3048 2433);
DISPLAY 0.489362 (-3048 2433);
PAINT MONO (-3048 2433);
FORCEPROP 2 LAST CDS_LIB standard
J 0
(-3050 2425);
DISPLAY INVISIBLE (-3050 2425);
FORCEPROP 2 LAST BOM_COST IO_SLOT
J 0
(-3550 2525);
DISPLAY 0.829787 (-3550 2525);
DISPLAY INVISIBLE (-3550 2525);
FORCEPROP 2 LAST ROOM RISER1
J 0
(-3550 2475);
DISPLAY 0.829787 (-3550 2475);
PAINT RED (-3550 2475);
DISPLAY INVISIBLE (-3550 2475);
FORCEPROP 1 LAST BODY_TYPE PLUMBING
J 2
(-3050 2375);
DISPLAY 0.702128 (-3050 2375);
PAINT GREEN (-3050 2375);
DISPLAY INVISIBLE (-3050 2375);
FORCEPROP 1 LAST HDL_TAP TRUE
J 2
(-3375 2300);
DISPLAY 0.702128 (-3375 2300);
PAINT GREEN (-3375 2300);
DISPLAY INVISIBLE (-3375 2300);
FORCEPROP 1 LAST PATH I247
J 2
(-3048 2425);
DISPLAY 0.872340 (-3048 2425);
PAINT GREEN (-3048 2425);
DISPLAY INVISIBLE (-3048 2425);
FORCEADD TAP..6
R 2
(-3050 2525);
FORCEPROP 3 LASTPIN (-3100 2525) SIG_NAME GMI_CPU1_G3_CPU0_G1_TX_DP<9>
J 0
(-3090 2535);
DISPLAY 0.659574 (-3090 2535);
PAINT MONO (-3090 2535);
DISPLAY INVISIBLE (-3090 2535);
FORCEPROP 1 LASTPIN (-3100 2525) BN 9
J 2
(-3048 2533);
DISPLAY 0.489362 (-3048 2533);
PAINT MONO (-3048 2533);
FORCEPROP 2 LAST CDS_LIB standard
J 0
(-3050 2525);
DISPLAY INVISIBLE (-3050 2525);
FORCEPROP 2 LAST BOM_COST IO_SLOT
J 0
(-3550 2625);
DISPLAY 0.829787 (-3550 2625);
DISPLAY INVISIBLE (-3550 2625);
FORCEPROP 2 LAST ROOM RISER1
J 0
(-3550 2575);
DISPLAY 0.829787 (-3550 2575);
PAINT RED (-3550 2575);
DISPLAY INVISIBLE (-3550 2575);
FORCEPROP 1 LAST BODY_TYPE PLUMBING
J 2
(-3050 2475);
DISPLAY 0.702128 (-3050 2475);
PAINT GREEN (-3050 2475);
DISPLAY INVISIBLE (-3050 2475);
FORCEPROP 1 LAST HDL_TAP TRUE
J 2
(-3375 2400);
DISPLAY 0.702128 (-3375 2400);
PAINT GREEN (-3375 2400);
DISPLAY INVISIBLE (-3375 2400);
FORCEPROP 1 LAST PATH I248
J 2
(-3048 2525);
DISPLAY 0.872340 (-3048 2525);
PAINT GREEN (-3048 2525);
DISPLAY INVISIBLE (-3048 2525);
FORCEADD TAP..6
R 2
(-3050 2325);
FORCEPROP 3 LASTPIN (-3100 2325) SIG_NAME GMI_CPU1_G3_CPU0_G1_TX_DP<7>
J 0
(-3090 2335);
DISPLAY 0.659574 (-3090 2335);
PAINT MONO (-3090 2335);
DISPLAY INVISIBLE (-3090 2335);
FORCEPROP 1 LASTPIN (-3100 2325) BN 7
J 2
(-3048 2333);
DISPLAY 0.489362 (-3048 2333);
PAINT MONO (-3048 2333);
FORCEPROP 2 LAST CDS_LIB standard
J 0
(-3050 2325);
DISPLAY INVISIBLE (-3050 2325);
FORCEPROP 2 LAST BOM_COST IO_SLOT
J 0
(-3550 2425);
DISPLAY 0.829787 (-3550 2425);
DISPLAY INVISIBLE (-3550 2425);
FORCEPROP 2 LAST ROOM RISER1
J 0
(-3550 2375);
DISPLAY 0.829787 (-3550 2375);
PAINT RED (-3550 2375);
DISPLAY INVISIBLE (-3550 2375);
FORCEPROP 1 LAST BODY_TYPE PLUMBING
J 2
(-3050 2275);
DISPLAY 0.702128 (-3050 2275);
PAINT GREEN (-3050 2275);
DISPLAY INVISIBLE (-3050 2275);
FORCEPROP 1 LAST HDL_TAP TRUE
J 2
(-3375 2200);
DISPLAY 0.702128 (-3375 2200);
PAINT GREEN (-3375 2200);
DISPLAY INVISIBLE (-3375 2200);
FORCEPROP 1 LAST PATH I249
J 2
(-3048 2325);
DISPLAY 0.872340 (-3048 2325);
PAINT GREEN (-3048 2325);
DISPLAY INVISIBLE (-3048 2325);
FORCEADD TAP..6
R 2
(-3050 2225);
FORCEPROP 3 LASTPIN (-3100 2225) SIG_NAME GMI_CPU1_G3_CPU0_G1_TX_DP<6>
J 0
(-3090 2235);
DISPLAY 0.659574 (-3090 2235);
PAINT MONO (-3090 2235);
DISPLAY INVISIBLE (-3090 2235);
FORCEPROP 1 LASTPIN (-3100 2225) BN 6
J 2
(-3048 2233);
DISPLAY 0.489362 (-3048 2233);
PAINT MONO (-3048 2233);
FORCEPROP 2 LAST CDS_LIB standard
J 0
(-3050 2225);
DISPLAY INVISIBLE (-3050 2225);
FORCEPROP 2 LAST BOM_COST IO_SLOT
J 0
(-3550 2325);
DISPLAY 0.829787 (-3550 2325);
DISPLAY INVISIBLE (-3550 2325);
FORCEPROP 2 LAST ROOM RISER1
J 0
(-3550 2275);
DISPLAY 0.829787 (-3550 2275);
PAINT RED (-3550 2275);
DISPLAY INVISIBLE (-3550 2275);
FORCEPROP 1 LAST BODY_TYPE PLUMBING
J 2
(-3050 2175);
DISPLAY 0.702128 (-3050 2175);
PAINT GREEN (-3050 2175);
DISPLAY INVISIBLE (-3050 2175);
FORCEPROP 1 LAST HDL_TAP TRUE
J 2
(-3375 2100);
DISPLAY 0.702128 (-3375 2100);
PAINT GREEN (-3375 2100);
DISPLAY INVISIBLE (-3375 2100);
FORCEPROP 1 LAST PATH I250
J 2
(-3048 2225);
DISPLAY 0.872340 (-3048 2225);
PAINT GREEN (-3048 2225);
DISPLAY INVISIBLE (-3048 2225);
FORCEADD TAP..6
R 2
(-3050 2125);
FORCEPROP 3 LASTPIN (-3100 2125) SIG_NAME GMI_CPU1_G3_CPU0_G1_TX_DP<5>
J 0
(-3090 2135);
DISPLAY 0.659574 (-3090 2135);
PAINT MONO (-3090 2135);
DISPLAY INVISIBLE (-3090 2135);
FORCEPROP 1 LASTPIN (-3100 2125) BN 5
J 2
(-3048 2133);
DISPLAY 0.489362 (-3048 2133);
PAINT MONO (-3048 2133);
FORCEPROP 2 LAST CDS_LIB standard
J 0
(-3050 2125);
DISPLAY INVISIBLE (-3050 2125);
FORCEPROP 2 LAST BOM_COST IO_SLOT
J 0
(-3550 2225);
DISPLAY 0.829787 (-3550 2225);
DISPLAY INVISIBLE (-3550 2225);
FORCEPROP 2 LAST ROOM RISER1
J 0
(-3550 2175);
DISPLAY 0.829787 (-3550 2175);
PAINT RED (-3550 2175);
DISPLAY INVISIBLE (-3550 2175);
FORCEPROP 1 LAST BODY_TYPE PLUMBING
J 2
(-3050 2075);
DISPLAY 0.702128 (-3050 2075);
PAINT GREEN (-3050 2075);
DISPLAY INVISIBLE (-3050 2075);
FORCEPROP 1 LAST HDL_TAP TRUE
J 2
(-3375 2000);
DISPLAY 0.702128 (-3375 2000);
PAINT GREEN (-3375 2000);
DISPLAY INVISIBLE (-3375 2000);
FORCEPROP 1 LAST PATH I251
J 2
(-3048 2125);
DISPLAY 0.872340 (-3048 2125);
PAINT GREEN (-3048 2125);
DISPLAY INVISIBLE (-3048 2125);
FORCEADD TAP..6
R 2
(-3050 1825);
FORCEPROP 3 LASTPIN (-3100 1825) SIG_NAME GMI_CPU1_G3_CPU0_G1_TX_DP<2>
J 0
(-3090 1835);
DISPLAY 0.659574 (-3090 1835);
PAINT MONO (-3090 1835);
DISPLAY INVISIBLE (-3090 1835);
FORCEPROP 1 LASTPIN (-3100 1825) BN 2
J 2
(-3048 1833);
DISPLAY 0.489362 (-3048 1833);
PAINT MONO (-3048 1833);
FORCEPROP 2 LAST CDS_LIB standard
J 0
(-3050 1825);
DISPLAY INVISIBLE (-3050 1825);
FORCEPROP 2 LAST BOM_COST IO_SLOT
J 0
(-3550 1925);
DISPLAY 0.829787 (-3550 1925);
DISPLAY INVISIBLE (-3550 1925);
FORCEPROP 2 LAST ROOM RISER1
J 0
(-3550 1875);
DISPLAY 0.829787 (-3550 1875);
PAINT RED (-3550 1875);
DISPLAY INVISIBLE (-3550 1875);
FORCEPROP 1 LAST BODY_TYPE PLUMBING
J 2
(-3050 1775);
DISPLAY 0.702128 (-3050 1775);
PAINT GREEN (-3050 1775);
DISPLAY INVISIBLE (-3050 1775);
FORCEPROP 1 LAST HDL_TAP TRUE
J 2
(-3375 1700);
DISPLAY 0.702128 (-3375 1700);
PAINT GREEN (-3375 1700);
DISPLAY INVISIBLE (-3375 1700);
FORCEPROP 1 LAST PATH I257
J 2
(-3048 1825);
DISPLAY 0.872340 (-3048 1825);
PAINT GREEN (-3048 1825);
DISPLAY INVISIBLE (-3048 1825);
FORCEADD TAP..6
R 2
(-3050 2025);
FORCEPROP 3 LASTPIN (-3100 2025) SIG_NAME GMI_CPU1_G3_CPU0_G1_TX_DP<4>
J 0
(-3090 2035);
DISPLAY 0.659574 (-3090 2035);
PAINT MONO (-3090 2035);
DISPLAY INVISIBLE (-3090 2035);
FORCEPROP 1 LASTPIN (-3100 2025) BN 4
J 2
(-3048 2033);
DISPLAY 0.489362 (-3048 2033);
PAINT MONO (-3048 2033);
FORCEPROP 2 LAST CDS_LIB standard
J 0
(-3050 2025);
DISPLAY INVISIBLE (-3050 2025);
FORCEPROP 2 LAST BOM_COST IO_SLOT
J 0
(-3550 2125);
DISPLAY 0.829787 (-3550 2125);
DISPLAY INVISIBLE (-3550 2125);
FORCEPROP 2 LAST ROOM RISER1
J 0
(-3550 2075);
DISPLAY 0.829787 (-3550 2075);
PAINT RED (-3550 2075);
DISPLAY INVISIBLE (-3550 2075);
FORCEPROP 1 LAST BODY_TYPE PLUMBING
J 2
(-3050 1975);
DISPLAY 0.702128 (-3050 1975);
PAINT GREEN (-3050 1975);
DISPLAY INVISIBLE (-3050 1975);
FORCEPROP 1 LAST HDL_TAP TRUE
J 2
(-3375 1900);
DISPLAY 0.702128 (-3375 1900);
PAINT GREEN (-3375 1900);
DISPLAY INVISIBLE (-3375 1900);
FORCEPROP 1 LAST PATH I258
J 2
(-3048 2025);
DISPLAY 0.872340 (-3048 2025);
PAINT GREEN (-3048 2025);
DISPLAY INVISIBLE (-3048 2025);
FORCEADD TAP..6
R 2
(-3050 1925);
FORCEPROP 3 LASTPIN (-3100 1925) SIG_NAME GMI_CPU1_G3_CPU0_G1_TX_DP<3>
J 0
(-3090 1935);
DISPLAY 0.659574 (-3090 1935);
PAINT MONO (-3090 1935);
DISPLAY INVISIBLE (-3090 1935);
FORCEPROP 1 LASTPIN (-3100 1925) BN 3
J 2
(-3048 1933);
DISPLAY 0.489362 (-3048 1933);
PAINT MONO (-3048 1933);
FORCEPROP 2 LAST CDS_LIB standard
J 0
(-3050 1925);
DISPLAY INVISIBLE (-3050 1925);
FORCEPROP 2 LAST BOM_COST IO_SLOT
J 0
(-3550 2025);
DISPLAY 0.829787 (-3550 2025);
DISPLAY INVISIBLE (-3550 2025);
FORCEPROP 2 LAST ROOM RISER1
J 0
(-3550 1975);
DISPLAY 0.829787 (-3550 1975);
PAINT RED (-3550 1975);
DISPLAY INVISIBLE (-3550 1975);
FORCEPROP 1 LAST BODY_TYPE PLUMBING
J 2
(-3050 1875);
DISPLAY 0.702128 (-3050 1875);
PAINT GREEN (-3050 1875);
DISPLAY INVISIBLE (-3050 1875);
FORCEPROP 1 LAST HDL_TAP TRUE
J 2
(-3375 1800);
DISPLAY 0.702128 (-3375 1800);
PAINT GREEN (-3375 1800);
DISPLAY INVISIBLE (-3375 1800);
FORCEPROP 1 LAST PATH I259
J 2
(-3048 1925);
DISPLAY 0.872340 (-3048 1925);
PAINT GREEN (-3048 1925);
DISPLAY INVISIBLE (-3048 1925);
FORCEADD TAP..6
R 2
(-3050 1725);
FORCEPROP 3 LASTPIN (-3100 1725) SIG_NAME GMI_CPU1_G3_CPU0_G1_TX_DP<1>
J 0
(-3090 1735);
DISPLAY 0.659574 (-3090 1735);
PAINT MONO (-3090 1735);
DISPLAY INVISIBLE (-3090 1735);
FORCEPROP 1 LASTPIN (-3100 1725) BN 1
J 2
(-3048 1733);
DISPLAY 0.489362 (-3048 1733);
PAINT MONO (-3048 1733);
FORCEPROP 2 LAST CDS_LIB standard
J 0
(-3050 1725);
DISPLAY INVISIBLE (-3050 1725);
FORCEPROP 2 LAST BOM_COST IO_SLOT
J 0
(-3550 1825);
DISPLAY 0.829787 (-3550 1825);
DISPLAY INVISIBLE (-3550 1825);
FORCEPROP 2 LAST ROOM RISER1
J 0
(-3550 1775);
DISPLAY 0.829787 (-3550 1775);
PAINT RED (-3550 1775);
DISPLAY INVISIBLE (-3550 1775);
FORCEPROP 1 LAST BODY_TYPE PLUMBING
J 2
(-3050 1675);
DISPLAY 0.702128 (-3050 1675);
PAINT GREEN (-3050 1675);
DISPLAY INVISIBLE (-3050 1675);
FORCEPROP 1 LAST HDL_TAP TRUE
J 2
(-3375 1600);
DISPLAY 0.702128 (-3375 1600);
PAINT GREEN (-3375 1600);
DISPLAY INVISIBLE (-3375 1600);
FORCEPROP 1 LAST PATH I260
J 2
(-3048 1725);
DISPLAY 0.872340 (-3048 1725);
PAINT GREEN (-3048 1725);
DISPLAY INVISIBLE (-3048 1725);
FORCEADD TAP..6
R 2
(-3050 1625);
FORCEPROP 3 LASTPIN (-3100 1625) SIG_NAME GMI_CPU1_G3_CPU0_G1_TX_DP<0>
J 0
(-3090 1635);
DISPLAY 0.659574 (-3090 1635);
PAINT MONO (-3090 1635);
DISPLAY INVISIBLE (-3090 1635);
FORCEPROP 1 LASTPIN (-3100 1625) BN 0
J 2
(-3048 1633);
DISPLAY 0.489362 (-3048 1633);
PAINT MONO (-3048 1633);
FORCEPROP 2 LAST CDS_LIB standard
J 0
(-3050 1625);
DISPLAY INVISIBLE (-3050 1625);
FORCEPROP 2 LAST BOM_COST IO_SLOT
J 0
(-3550 1725);
DISPLAY 0.829787 (-3550 1725);
DISPLAY INVISIBLE (-3550 1725);
FORCEPROP 2 LAST ROOM RISER1
J 0
(-3550 1675);
DISPLAY 0.829787 (-3550 1675);
PAINT RED (-3550 1675);
DISPLAY INVISIBLE (-3550 1675);
FORCEPROP 1 LAST BODY_TYPE PLUMBING
J 2
(-3050 1575);
DISPLAY 0.702128 (-3050 1575);
PAINT GREEN (-3050 1575);
DISPLAY INVISIBLE (-3050 1575);
FORCEPROP 1 LAST HDL_TAP TRUE
J 2
(-3375 1500);
DISPLAY 0.702128 (-3375 1500);
PAINT GREEN (-3375 1500);
DISPLAY INVISIBLE (-3375 1500);
FORCEPROP 1 LAST PATH I261
J 2
(-3048 1625);
DISPLAY 0.872340 (-3048 1625);
PAINT GREEN (-3048 1625);
DISPLAY INVISIBLE (-3048 1625);
FORCEADD TAP..6
(-6500 5800);
FORCEPROP 3 LASTPIN (-6450 5800) SIG_NAME GMI_CPU0_G0_CPU1_G2_TX_DP<15>
J 0
(-6440 5810);
DISPLAY 0.659574 (-6440 5810);
PAINT MONO (-6440 5810);
DISPLAY INVISIBLE (-6440 5810);
FORCEPROP 1 LASTPIN (-6450 5800) BN 15
J 0
(-6502 5808);
DISPLAY 0.489362 (-6502 5808);
PAINT MONO (-6502 5808);
FORCEPROP 2 LAST CDS_LIB mstr_standard
J 0
(-6500 5800);
DISPLAY INVISIBLE (-6500 5800);
FORCEPROP 1 LAST BODY_TYPE PLUMBING
J 0
(-6500 5750);
DISPLAY 0.574468 (-6500 5750);
PAINT GREEN (-6500 5750);
DISPLAY INVISIBLE (-6500 5750);
FORCEPROP 1 LAST HDL_TAP TRUE
J 0
(-6175 5675);
DISPLAY 0.574468 (-6175 5675);
PAINT GREEN (-6175 5675);
DISPLAY INVISIBLE (-6175 5675);
FORCEPROP 1 LAST PATH I262
J 0
(-6502 5800);
DISPLAY 0.872340 (-6502 5800);
PAINT GREEN (-6502 5800);
DISPLAY INVISIBLE (-6502 5800);
FORCEADD TAP..6
(-6500 5700);
FORCEPROP 3 LASTPIN (-6450 5700) SIG_NAME GMI_CPU0_G0_CPU1_G2_TX_DP<14>
J 0
(-6440 5710);
DISPLAY 0.659574 (-6440 5710);
PAINT MONO (-6440 5710);
DISPLAY INVISIBLE (-6440 5710);
FORCEPROP 1 LASTPIN (-6450 5700) BN 14
J 0
(-6502 5708);
DISPLAY 0.489362 (-6502 5708);
PAINT MONO (-6502 5708);
FORCEPROP 2 LAST CDS_LIB mstr_standard
J 0
(-6500 5700);
DISPLAY INVISIBLE (-6500 5700);
FORCEPROP 1 LAST BODY_TYPE PLUMBING
J 0
(-6500 5650);
DISPLAY 0.574468 (-6500 5650);
PAINT GREEN (-6500 5650);
DISPLAY INVISIBLE (-6500 5650);
FORCEPROP 1 LAST HDL_TAP TRUE
J 0
(-6175 5575);
DISPLAY 0.574468 (-6175 5575);
PAINT GREEN (-6175 5575);
DISPLAY INVISIBLE (-6175 5575);
FORCEPROP 1 LAST PATH I263
J 0
(-6502 5700);
DISPLAY 0.872340 (-6502 5700);
PAINT GREEN (-6502 5700);
DISPLAY INVISIBLE (-6502 5700);
FORCEADD TAP..6
(-6500 5600);
FORCEPROP 3 LASTPIN (-6450 5600) SIG_NAME GMI_CPU0_G0_CPU1_G2_TX_DP<13>
J 0
(-6440 5610);
DISPLAY 0.659574 (-6440 5610);
PAINT MONO (-6440 5610);
DISPLAY INVISIBLE (-6440 5610);
FORCEPROP 1 LASTPIN (-6450 5600) BN 13
J 0
(-6502 5608);
DISPLAY 0.489362 (-6502 5608);
PAINT MONO (-6502 5608);
FORCEPROP 2 LAST CDS_LIB mstr_standard
J 0
(-6500 5600);
DISPLAY INVISIBLE (-6500 5600);
FORCEPROP 1 LAST BODY_TYPE PLUMBING
J 0
(-6500 5550);
DISPLAY 0.574468 (-6500 5550);
PAINT GREEN (-6500 5550);
DISPLAY INVISIBLE (-6500 5550);
FORCEPROP 1 LAST HDL_TAP TRUE
J 0
(-6175 5475);
DISPLAY 0.574468 (-6175 5475);
PAINT GREEN (-6175 5475);
DISPLAY INVISIBLE (-6175 5475);
FORCEPROP 1 LAST PATH I266
J 0
(-6502 5600);
DISPLAY 0.872340 (-6502 5600);
PAINT GREEN (-6502 5600);
DISPLAY INVISIBLE (-6502 5600);
FORCEADD TAP..6
(-6500 5500);
FORCEPROP 3 LASTPIN (-6450 5500) SIG_NAME GMI_CPU0_G0_CPU1_G2_TX_DP<12>
J 0
(-6440 5510);
DISPLAY 0.659574 (-6440 5510);
PAINT MONO (-6440 5510);
DISPLAY INVISIBLE (-6440 5510);
FORCEPROP 1 LASTPIN (-6450 5500) BN 12
J 0
(-6502 5508);
DISPLAY 0.489362 (-6502 5508);
PAINT MONO (-6502 5508);
FORCEPROP 2 LAST CDS_LIB standard
J 0
(-6500 5500);
DISPLAY INVISIBLE (-6500 5500);
FORCEPROP 1 LAST BODY_TYPE PLUMBING
J 0
(-6500 5450);
DISPLAY 0.574468 (-6500 5450);
PAINT GREEN (-6500 5450);
DISPLAY INVISIBLE (-6500 5450);
FORCEPROP 1 LAST HDL_TAP TRUE
J 0
(-6175 5375);
DISPLAY 0.574468 (-6175 5375);
PAINT GREEN (-6175 5375);
DISPLAY INVISIBLE (-6175 5375);
FORCEPROP 1 LAST PATH I267
J 0
(-6502 5500);
DISPLAY 0.872340 (-6502 5500);
PAINT GREEN (-6502 5500);
DISPLAY INVISIBLE (-6502 5500);
FORCEADD TAP..6
(-6500 5400);
FORCEPROP 3 LASTPIN (-6450 5400) SIG_NAME GMI_CPU0_G0_CPU1_G2_TX_DP<11>
J 0
(-6440 5410);
DISPLAY 0.659574 (-6440 5410);
PAINT MONO (-6440 5410);
DISPLAY INVISIBLE (-6440 5410);
FORCEPROP 1 LASTPIN (-6450 5400) BN 11
J 0
(-6502 5408);
DISPLAY 0.489362 (-6502 5408);
PAINT MONO (-6502 5408);
FORCEPROP 2 LAST CDS_LIB standard
J 0
(-6500 5400);
DISPLAY INVISIBLE (-6500 5400);
FORCEPROP 1 LAST BODY_TYPE PLUMBING
J 0
(-6500 5350);
DISPLAY 0.574468 (-6500 5350);
PAINT GREEN (-6500 5350);
DISPLAY INVISIBLE (-6500 5350);
FORCEPROP 1 LAST HDL_TAP TRUE
J 0
(-6175 5275);
DISPLAY 0.574468 (-6175 5275);
PAINT GREEN (-6175 5275);
DISPLAY INVISIBLE (-6175 5275);
FORCEPROP 1 LAST PATH I268
J 0
(-6502 5400);
DISPLAY 0.872340 (-6502 5400);
PAINT GREEN (-6502 5400);
DISPLAY INVISIBLE (-6502 5400);
FORCEADD TAP..6
(-6500 5300);
FORCEPROP 3 LASTPIN (-6450 5300) SIG_NAME GMI_CPU0_G0_CPU1_G2_TX_DP<10>
J 0
(-6440 5310);
DISPLAY 0.659574 (-6440 5310);
PAINT MONO (-6440 5310);
DISPLAY INVISIBLE (-6440 5310);
FORCEPROP 1 LASTPIN (-6450 5300) BN 10
J 0
(-6502 5308);
DISPLAY 0.489362 (-6502 5308);
PAINT MONO (-6502 5308);
FORCEPROP 2 LAST CDS_LIB standard
J 0
(-6500 5300);
DISPLAY INVISIBLE (-6500 5300);
FORCEPROP 1 LAST BODY_TYPE PLUMBING
J 0
(-6500 5250);
DISPLAY 0.574468 (-6500 5250);
PAINT GREEN (-6500 5250);
DISPLAY INVISIBLE (-6500 5250);
FORCEPROP 1 LAST HDL_TAP TRUE
J 0
(-6175 5175);
DISPLAY 0.574468 (-6175 5175);
PAINT GREEN (-6175 5175);
DISPLAY INVISIBLE (-6175 5175);
FORCEPROP 1 LAST PATH I271
J 0
(-6502 5300);
DISPLAY 0.872340 (-6502 5300);
PAINT GREEN (-6502 5300);
DISPLAY INVISIBLE (-6502 5300);
FORCEADD TAP..6
(-6500 5200);
FORCEPROP 3 LASTPIN (-6450 5200) SIG_NAME GMI_CPU0_G0_CPU1_G2_TX_DP<9>
J 0
(-6440 5210);
DISPLAY 0.659574 (-6440 5210);
PAINT MONO (-6440 5210);
DISPLAY INVISIBLE (-6440 5210);
FORCEPROP 1 LASTPIN (-6450 5200) BN 9
J 0
(-6502 5208);
DISPLAY 0.489362 (-6502 5208);
PAINT MONO (-6502 5208);
FORCEPROP 2 LAST CDS_LIB standard
J 0
(-6500 5200);
DISPLAY INVISIBLE (-6500 5200);
FORCEPROP 1 LAST BODY_TYPE PLUMBING
J 0
(-6500 5150);
DISPLAY 0.574468 (-6500 5150);
PAINT GREEN (-6500 5150);
DISPLAY INVISIBLE (-6500 5150);
FORCEPROP 1 LAST HDL_TAP TRUE
J 0
(-6175 5075);
DISPLAY 0.574468 (-6175 5075);
PAINT GREEN (-6175 5075);
DISPLAY INVISIBLE (-6175 5075);
FORCEPROP 1 LAST PATH I272
J 0
(-6502 5200);
DISPLAY 0.872340 (-6502 5200);
PAINT GREEN (-6502 5200);
DISPLAY INVISIBLE (-6502 5200);
FORCEADD TAP..6
(-6500 5100);
FORCEPROP 3 LASTPIN (-6450 5100) SIG_NAME GMI_CPU0_G0_CPU1_G2_TX_DP<8>
J 0
(-6440 5110);
DISPLAY 0.659574 (-6440 5110);
PAINT MONO (-6440 5110);
DISPLAY INVISIBLE (-6440 5110);
FORCEPROP 1 LASTPIN (-6450 5100) BN 8
J 0
(-6502 5108);
DISPLAY 0.489362 (-6502 5108);
PAINT MONO (-6502 5108);
FORCEPROP 2 LAST CDS_LIB standard
J 0
(-6500 5100);
DISPLAY INVISIBLE (-6500 5100);
FORCEPROP 1 LAST BODY_TYPE PLUMBING
J 0
(-6500 5050);
DISPLAY 0.574468 (-6500 5050);
PAINT GREEN (-6500 5050);
DISPLAY INVISIBLE (-6500 5050);
FORCEPROP 1 LAST HDL_TAP TRUE
J 0
(-6175 4975);
DISPLAY 0.574468 (-6175 4975);
PAINT GREEN (-6175 4975);
DISPLAY INVISIBLE (-6175 4975);
FORCEPROP 1 LAST PATH I276
J 0
(-6502 5100);
DISPLAY 0.872340 (-6502 5100);
PAINT GREEN (-6502 5100);
DISPLAY INVISIBLE (-6502 5100);
FORCEADD TAP..6
(-6500 4900);
FORCEPROP 3 LASTPIN (-6450 4900) SIG_NAME GMI_CPU0_G0_CPU1_G2_TX_DP<6>
J 0
(-6440 4910);
DISPLAY 0.659574 (-6440 4910);
PAINT MONO (-6440 4910);
DISPLAY INVISIBLE (-6440 4910);
FORCEPROP 1 LASTPIN (-6450 4900) BN 6
J 0
(-6502 4908);
DISPLAY 0.489362 (-6502 4908);
PAINT MONO (-6502 4908);
FORCEPROP 2 LAST CDS_LIB standard
J 0
(-6500 4900);
DISPLAY INVISIBLE (-6500 4900);
FORCEPROP 1 LAST BODY_TYPE PLUMBING
J 0
(-6500 4850);
DISPLAY 0.574468 (-6500 4850);
PAINT GREEN (-6500 4850);
DISPLAY INVISIBLE (-6500 4850);
FORCEPROP 1 LAST HDL_TAP TRUE
J 0
(-6175 4775);
DISPLAY 0.574468 (-6175 4775);
PAINT GREEN (-6175 4775);
DISPLAY INVISIBLE (-6175 4775);
FORCEPROP 1 LAST PATH I277
J 0
(-6502 4900);
DISPLAY 0.872340 (-6502 4900);
PAINT GREEN (-6502 4900);
DISPLAY INVISIBLE (-6502 4900);
FORCEADD TAP..6
(-6500 5000);
FORCEPROP 3 LASTPIN (-6450 5000) SIG_NAME GMI_CPU0_G0_CPU1_G2_TX_DP<7>
J 0
(-6440 5010);
DISPLAY 0.659574 (-6440 5010);
PAINT MONO (-6440 5010);
DISPLAY INVISIBLE (-6440 5010);
FORCEPROP 1 LASTPIN (-6450 5000) BN 7
J 0
(-6502 5008);
DISPLAY 0.489362 (-6502 5008);
PAINT MONO (-6502 5008);
FORCEPROP 2 LAST CDS_LIB standard
J 0
(-6500 5000);
DISPLAY INVISIBLE (-6500 5000);
FORCEPROP 1 LAST BODY_TYPE PLUMBING
J 0
(-6500 4950);
DISPLAY 0.574468 (-6500 4950);
PAINT GREEN (-6500 4950);
DISPLAY INVISIBLE (-6500 4950);
FORCEPROP 1 LAST HDL_TAP TRUE
J 0
(-6175 4875);
DISPLAY 0.574468 (-6175 4875);
PAINT GREEN (-6175 4875);
DISPLAY INVISIBLE (-6175 4875);
FORCEPROP 1 LAST PATH I278
J 0
(-6502 5000);
DISPLAY 0.872340 (-6502 5000);
PAINT GREEN (-6502 5000);
DISPLAY INVISIBLE (-6502 5000);
FORCEADD TAP..6
(-6500 4800);
FORCEPROP 3 LASTPIN (-6450 4800) SIG_NAME GMI_CPU0_G0_CPU1_G2_TX_DP<5>
J 0
(-6440 4810);
DISPLAY 0.659574 (-6440 4810);
PAINT MONO (-6440 4810);
DISPLAY INVISIBLE (-6440 4810);
FORCEPROP 1 LASTPIN (-6450 4800) BN 5
J 0
(-6502 4808);
DISPLAY 0.489362 (-6502 4808);
PAINT MONO (-6502 4808);
FORCEPROP 2 LAST CDS_LIB standard
J 0
(-6500 4800);
DISPLAY INVISIBLE (-6500 4800);
FORCEPROP 1 LAST BODY_TYPE PLUMBING
J 0
(-6500 4750);
DISPLAY 0.574468 (-6500 4750);
PAINT GREEN (-6500 4750);
DISPLAY INVISIBLE (-6500 4750);
FORCEPROP 1 LAST HDL_TAP TRUE
J 0
(-6175 4675);
DISPLAY 0.574468 (-6175 4675);
PAINT GREEN (-6175 4675);
DISPLAY INVISIBLE (-6175 4675);
FORCEPROP 1 LAST PATH I281
J 0
(-6502 4800);
DISPLAY 0.872340 (-6502 4800);
PAINT GREEN (-6502 4800);
DISPLAY INVISIBLE (-6502 4800);
FORCEADD TAP..6
(-6500 4700);
FORCEPROP 3 LASTPIN (-6450 4700) SIG_NAME GMI_CPU0_G0_CPU1_G2_TX_DP<4>
J 0
(-6440 4710);
DISPLAY 0.659574 (-6440 4710);
PAINT MONO (-6440 4710);
DISPLAY INVISIBLE (-6440 4710);
FORCEPROP 1 LASTPIN (-6450 4700) BN 4
J 0
(-6502 4708);
DISPLAY 0.489362 (-6502 4708);
PAINT MONO (-6502 4708);
FORCEPROP 2 LAST CDS_LIB standard
J 0
(-6500 4700);
DISPLAY INVISIBLE (-6500 4700);
FORCEPROP 1 LAST BODY_TYPE PLUMBING
J 0
(-6500 4650);
DISPLAY 0.574468 (-6500 4650);
PAINT GREEN (-6500 4650);
DISPLAY INVISIBLE (-6500 4650);
FORCEPROP 1 LAST HDL_TAP TRUE
J 0
(-6175 4575);
DISPLAY 0.574468 (-6175 4575);
PAINT GREEN (-6175 4575);
DISPLAY INVISIBLE (-6175 4575);
FORCEPROP 1 LAST PATH I282
J 0
(-6502 4700);
DISPLAY 0.872340 (-6502 4700);
PAINT GREEN (-6502 4700);
DISPLAY INVISIBLE (-6502 4700);
FORCEADD TAP..6
(-6500 4600);
FORCEPROP 3 LASTPIN (-6450 4600) SIG_NAME GMI_CPU0_G0_CPU1_G2_TX_DP<3>
J 0
(-6440 4610);
DISPLAY 0.659574 (-6440 4610);
PAINT MONO (-6440 4610);
DISPLAY INVISIBLE (-6440 4610);
FORCEPROP 1 LASTPIN (-6450 4600) BN 3
J 0
(-6502 4608);
DISPLAY 0.489362 (-6502 4608);
PAINT MONO (-6502 4608);
FORCEPROP 2 LAST CDS_LIB standard
J 0
(-6500 4600);
DISPLAY INVISIBLE (-6500 4600);
FORCEPROP 1 LAST BODY_TYPE PLUMBING
J 0
(-6500 4550);
DISPLAY 0.574468 (-6500 4550);
PAINT GREEN (-6500 4550);
DISPLAY INVISIBLE (-6500 4550);
FORCEPROP 1 LAST HDL_TAP TRUE
J 0
(-6175 4475);
DISPLAY 0.574468 (-6175 4475);
PAINT GREEN (-6175 4475);
DISPLAY INVISIBLE (-6175 4475);
FORCEPROP 1 LAST PATH I286
J 0
(-6502 4600);
DISPLAY 0.872340 (-6502 4600);
PAINT GREEN (-6502 4600);
DISPLAY INVISIBLE (-6502 4600);
FORCEADD TAP..6
(-6500 4400);
FORCEPROP 3 LASTPIN (-6450 4400) SIG_NAME GMI_CPU0_G0_CPU1_G2_TX_DP<1>
J 0
(-6440 4410);
DISPLAY 0.659574 (-6440 4410);
PAINT MONO (-6440 4410);
DISPLAY INVISIBLE (-6440 4410);
FORCEPROP 1 LASTPIN (-6450 4400) BN 1
J 0
(-6502 4408);
DISPLAY 0.489362 (-6502 4408);
PAINT MONO (-6502 4408);
FORCEPROP 2 LAST CDS_LIB standard
J 0
(-6500 4400);
DISPLAY INVISIBLE (-6500 4400);
FORCEPROP 1 LAST BODY_TYPE PLUMBING
J 0
(-6500 4350);
DISPLAY 0.574468 (-6500 4350);
PAINT GREEN (-6500 4350);
DISPLAY INVISIBLE (-6500 4350);
FORCEPROP 1 LAST HDL_TAP TRUE
J 0
(-6175 4275);
DISPLAY 0.574468 (-6175 4275);
PAINT GREEN (-6175 4275);
DISPLAY INVISIBLE (-6175 4275);
FORCEPROP 1 LAST PATH I287
J 0
(-6502 4400);
DISPLAY 0.872340 (-6502 4400);
PAINT GREEN (-6502 4400);
DISPLAY INVISIBLE (-6502 4400);
FORCEADD TAP..6
(-6500 4500);
FORCEPROP 3 LASTPIN (-6450 4500) SIG_NAME GMI_CPU0_G0_CPU1_G2_TX_DP<2>
J 0
(-6440 4510);
DISPLAY 0.659574 (-6440 4510);
PAINT MONO (-6440 4510);
DISPLAY INVISIBLE (-6440 4510);
FORCEPROP 1 LASTPIN (-6450 4500) BN 2
J 0
(-6502 4508);
DISPLAY 0.489362 (-6502 4508);
PAINT MONO (-6502 4508);
FORCEPROP 2 LAST CDS_LIB standard
J 0
(-6500 4500);
DISPLAY INVISIBLE (-6500 4500);
FORCEPROP 1 LAST BODY_TYPE PLUMBING
J 0
(-6500 4450);
DISPLAY 0.574468 (-6500 4450);
PAINT GREEN (-6500 4450);
DISPLAY INVISIBLE (-6500 4450);
FORCEPROP 1 LAST HDL_TAP TRUE
J 0
(-6175 4375);
DISPLAY 0.574468 (-6175 4375);
PAINT GREEN (-6175 4375);
DISPLAY INVISIBLE (-6175 4375);
FORCEPROP 1 LAST PATH I288
J 0
(-6502 4500);
DISPLAY 0.872340 (-6502 4500);
PAINT GREEN (-6502 4500);
DISPLAY INVISIBLE (-6502 4500);
FORCEADD TAP..6
(-6500 4300);
FORCEPROP 3 LASTPIN (-6450 4300) SIG_NAME GMI_CPU0_G0_CPU1_G2_TX_DP<0>
J 0
(-6440 4310);
DISPLAY 0.659574 (-6440 4310);
PAINT MONO (-6440 4310);
DISPLAY INVISIBLE (-6440 4310);
FORCEPROP 1 LASTPIN (-6450 4300) BN 0
J 0
(-6502 4308);
DISPLAY 0.489362 (-6502 4308);
PAINT MONO (-6502 4308);
FORCEPROP 2 LAST CDS_LIB standard
J 0
(-6500 4300);
DISPLAY INVISIBLE (-6500 4300);
FORCEPROP 1 LAST BODY_TYPE PLUMBING
J 0
(-6500 4250);
DISPLAY 0.574468 (-6500 4250);
PAINT GREEN (-6500 4250);
DISPLAY INVISIBLE (-6500 4250);
FORCEPROP 1 LAST HDL_TAP TRUE
J 0
(-6175 4175);
DISPLAY 0.574468 (-6175 4175);
PAINT GREEN (-6175 4175);
DISPLAY INVISIBLE (-6175 4175);
FORCEPROP 1 LAST PATH I291
J 0
(-6502 4300);
DISPLAY 0.872340 (-6502 4300);
PAINT GREEN (-6502 4300);
DISPLAY INVISIBLE (-6502 4300);
FORCEADD OFFPAGE..1
(-7700 6025);
FORCEPROP 2 LAST $XR0 22 
J 0
(-7951 6025);
DISPLAY 0.638298 (-7951 6025);
PAINT MONO (-7951 6025);
FORCEPROP 2 LAST CDS_LIB standard
J 0
(-7700 6025);
DISPLAY INVISIBLE (-7700 6025);
FORCEPROP 1 LAST OFFPAGE TRUE
J 0
(-7375 5900);
DISPLAY 0.872340 (-7375 5900);
PAINT GREEN (-7375 5900);
DISPLAY INVISIBLE (-7375 5900);
FORCEPROP 1 LAST COMMENT_BODY TRUE
J 0
(-7575 5925);
DISPLAY 0.872340 (-7575 5925);
PAINT GREEN (-7575 5925);
DISPLAY INVISIBLE (-7575 5925);
FORCEPROP 2 LAST PATH I295
J 0
(-7900 6075);
DISPLAY 1.021277 (-7900 6075);
DISPLAY INVISIBLE (-7900 6075);
FORCEADD TAP..6
(-6475 3125);
FORCEPROP 3 LASTPIN (-6425 3125) SIG_NAME GMI_CPU0_G1_CPU1_G3_TX_DP<15>
J 0
(-6415 3135);
DISPLAY 0.659574 (-6415 3135);
PAINT MONO (-6415 3135);
DISPLAY INVISIBLE (-6415 3135);
FORCEPROP 1 LASTPIN (-6425 3125) BN 15
J 0
(-6477 3133);
DISPLAY 0.489362 (-6477 3133);
PAINT MONO (-6477 3133);
FORCEPROP 2 LAST CDS_LIB standard
J 0
(-6475 3125);
DISPLAY INVISIBLE (-6475 3125);
FORCEPROP 1 LAST BODY_TYPE PLUMBING
J 0
(-6475 3075);
DISPLAY 0.574468 (-6475 3075);
PAINT GREEN (-6475 3075);
DISPLAY INVISIBLE (-6475 3075);
FORCEPROP 1 LAST HDL_TAP TRUE
J 0
(-6150 3000);
DISPLAY 0.574468 (-6150 3000);
PAINT GREEN (-6150 3000);
DISPLAY INVISIBLE (-6150 3000);
FORCEPROP 1 LAST PATH I296
J 0
(-6477 3125);
DISPLAY 0.872340 (-6477 3125);
PAINT GREEN (-6477 3125);
DISPLAY INVISIBLE (-6477 3125);
FORCEADD TAP..6
(-6475 2925);
FORCEPROP 3 LASTPIN (-6425 2925) SIG_NAME GMI_CPU0_G1_CPU1_G3_TX_DP<13>
J 0
(-6415 2935);
DISPLAY 0.659574 (-6415 2935);
PAINT MONO (-6415 2935);
DISPLAY INVISIBLE (-6415 2935);
FORCEPROP 1 LASTPIN (-6425 2925) BN 13
J 0
(-6477 2933);
DISPLAY 0.489362 (-6477 2933);
PAINT MONO (-6477 2933);
FORCEPROP 2 LAST CDS_LIB standard
J 0
(-6475 2925);
DISPLAY INVISIBLE (-6475 2925);
FORCEPROP 1 LAST BODY_TYPE PLUMBING
J 0
(-6475 2875);
DISPLAY 0.574468 (-6475 2875);
PAINT GREEN (-6475 2875);
DISPLAY INVISIBLE (-6475 2875);
FORCEPROP 1 LAST HDL_TAP TRUE
J 0
(-6150 2800);
DISPLAY 0.574468 (-6150 2800);
PAINT GREEN (-6150 2800);
DISPLAY INVISIBLE (-6150 2800);
FORCEPROP 1 LAST PATH I298
J 0
(-6477 2925);
DISPLAY 0.872340 (-6477 2925);
PAINT GREEN (-6477 2925);
DISPLAY INVISIBLE (-6477 2925);
FORCEADD TAP..6
(-6475 3025);
FORCEPROP 3 LASTPIN (-6425 3025) SIG_NAME GMI_CPU0_G1_CPU1_G3_TX_DP<14>
J 0
(-6415 3035);
DISPLAY 0.659574 (-6415 3035);
PAINT MONO (-6415 3035);
DISPLAY INVISIBLE (-6415 3035);
FORCEPROP 1 LASTPIN (-6425 3025) BN 14
J 0
(-6477 3033);
DISPLAY 0.489362 (-6477 3033);
PAINT MONO (-6477 3033);
FORCEPROP 2 LAST CDS_LIB standard
J 0
(-6475 3025);
DISPLAY INVISIBLE (-6475 3025);
FORCEPROP 1 LAST BODY_TYPE PLUMBING
J 0
(-6475 2975);
DISPLAY 0.574468 (-6475 2975);
PAINT GREEN (-6475 2975);
DISPLAY INVISIBLE (-6475 2975);
FORCEPROP 1 LAST HDL_TAP TRUE
J 0
(-6150 2900);
DISPLAY 0.574468 (-6150 2900);
PAINT GREEN (-6150 2900);
DISPLAY INVISIBLE (-6150 2900);
FORCEPROP 1 LAST PATH I299
J 0
(-6477 3025);
DISPLAY 0.872340 (-6477 3025);
PAINT GREEN (-6477 3025);
DISPLAY INVISIBLE (-6477 3025);
FORCEADD TAP..6
(-6475 2825);
FORCEPROP 3 LASTPIN (-6425 2825) SIG_NAME GMI_CPU0_G1_CPU1_G3_TX_DP<12>
J 0
(-6415 2835);
DISPLAY 0.659574 (-6415 2835);
PAINT MONO (-6415 2835);
DISPLAY INVISIBLE (-6415 2835);
FORCEPROP 1 LASTPIN (-6425 2825) BN 12
J 0
(-6477 2833);
DISPLAY 0.489362 (-6477 2833);
PAINT MONO (-6477 2833);
FORCEPROP 2 LAST CDS_LIB standard
J 0
(-6475 2825);
DISPLAY INVISIBLE (-6475 2825);
FORCEPROP 1 LAST BODY_TYPE PLUMBING
J 0
(-6475 2775);
DISPLAY 0.574468 (-6475 2775);
PAINT GREEN (-6475 2775);
DISPLAY INVISIBLE (-6475 2775);
FORCEPROP 1 LAST HDL_TAP TRUE
J 0
(-6150 2700);
DISPLAY 0.574468 (-6150 2700);
PAINT GREEN (-6150 2700);
DISPLAY INVISIBLE (-6150 2700);
FORCEPROP 1 LAST PATH I300
J 0
(-6477 2825);
DISPLAY 0.872340 (-6477 2825);
PAINT GREEN (-6477 2825);
DISPLAY INVISIBLE (-6477 2825);
FORCEADD TAP..6
(-6475 2725);
FORCEPROP 3 LASTPIN (-6425 2725) SIG_NAME GMI_CPU0_G1_CPU1_G3_TX_DP<11>
J 0
(-6415 2735);
DISPLAY 0.659574 (-6415 2735);
PAINT MONO (-6415 2735);
DISPLAY INVISIBLE (-6415 2735);
FORCEPROP 1 LASTPIN (-6425 2725) BN 11
J 0
(-6477 2733);
DISPLAY 0.489362 (-6477 2733);
PAINT MONO (-6477 2733);
FORCEPROP 2 LAST CDS_LIB standard
J 0
(-6475 2725);
DISPLAY INVISIBLE (-6475 2725);
FORCEPROP 1 LAST BODY_TYPE PLUMBING
J 0
(-6475 2675);
DISPLAY 0.574468 (-6475 2675);
PAINT GREEN (-6475 2675);
DISPLAY INVISIBLE (-6475 2675);
FORCEPROP 1 LAST HDL_TAP TRUE
J 0
(-6150 2600);
DISPLAY 0.574468 (-6150 2600);
PAINT GREEN (-6150 2600);
DISPLAY INVISIBLE (-6150 2600);
FORCEPROP 1 LAST PATH I303
J 0
(-6477 2725);
DISPLAY 0.872340 (-6477 2725);
PAINT GREEN (-6477 2725);
DISPLAY INVISIBLE (-6477 2725);
FORCEADD TAP..6
(-6475 2625);
FORCEPROP 3 LASTPIN (-6425 2625) SIG_NAME GMI_CPU0_G1_CPU1_G3_TX_DP<10>
J 0
(-6415 2635);
DISPLAY 0.659574 (-6415 2635);
PAINT MONO (-6415 2635);
DISPLAY INVISIBLE (-6415 2635);
FORCEPROP 1 LASTPIN (-6425 2625) BN 10
J 0
(-6477 2633);
DISPLAY 0.489362 (-6477 2633);
PAINT MONO (-6477 2633);
FORCEPROP 2 LAST CDS_LIB standard
J 0
(-6475 2625);
DISPLAY INVISIBLE (-6475 2625);
FORCEPROP 1 LAST BODY_TYPE PLUMBING
J 0
(-6475 2575);
DISPLAY 0.574468 (-6475 2575);
PAINT GREEN (-6475 2575);
DISPLAY INVISIBLE (-6475 2575);
FORCEPROP 1 LAST HDL_TAP TRUE
J 0
(-6150 2500);
DISPLAY 0.574468 (-6150 2500);
PAINT GREEN (-6150 2500);
DISPLAY INVISIBLE (-6150 2500);
FORCEPROP 1 LAST PATH I304
J 0
(-6477 2625);
DISPLAY 0.872340 (-6477 2625);
PAINT GREEN (-6477 2625);
DISPLAY INVISIBLE (-6477 2625);
FORCEADD TAP..6
(-6475 2425);
FORCEPROP 3 LASTPIN (-6425 2425) SIG_NAME GMI_CPU0_G1_CPU1_G3_TX_DP<8>
J 0
(-6415 2435);
DISPLAY 0.659574 (-6415 2435);
PAINT MONO (-6415 2435);
DISPLAY INVISIBLE (-6415 2435);
FORCEPROP 1 LASTPIN (-6425 2425) BN 8
J 0
(-6477 2433);
DISPLAY 0.489362 (-6477 2433);
PAINT MONO (-6477 2433);
FORCEPROP 2 LAST CDS_LIB standard
J 0
(-6475 2425);
DISPLAY INVISIBLE (-6475 2425);
FORCEPROP 1 LAST BODY_TYPE PLUMBING
J 0
(-6475 2375);
DISPLAY 0.574468 (-6475 2375);
PAINT GREEN (-6475 2375);
DISPLAY INVISIBLE (-6475 2375);
FORCEPROP 1 LAST HDL_TAP TRUE
J 0
(-6150 2300);
DISPLAY 0.574468 (-6150 2300);
PAINT GREEN (-6150 2300);
DISPLAY INVISIBLE (-6150 2300);
FORCEPROP 1 LAST PATH I308
J 0
(-6477 2425);
DISPLAY 0.872340 (-6477 2425);
PAINT GREEN (-6477 2425);
DISPLAY INVISIBLE (-6477 2425);
FORCEADD TAP..6
(-6475 2525);
FORCEPROP 3 LASTPIN (-6425 2525) SIG_NAME GMI_CPU0_G1_CPU1_G3_TX_DP<9>
J 0
(-6415 2535);
DISPLAY 0.659574 (-6415 2535);
PAINT MONO (-6415 2535);
DISPLAY INVISIBLE (-6415 2535);
FORCEPROP 1 LASTPIN (-6425 2525) BN 9
J 0
(-6477 2533);
DISPLAY 0.489362 (-6477 2533);
PAINT MONO (-6477 2533);
FORCEPROP 2 LAST CDS_LIB standard
J 0
(-6475 2525);
DISPLAY INVISIBLE (-6475 2525);
FORCEPROP 1 LAST BODY_TYPE PLUMBING
J 0
(-6475 2475);
DISPLAY 0.574468 (-6475 2475);
PAINT GREEN (-6475 2475);
DISPLAY INVISIBLE (-6475 2475);
FORCEPROP 1 LAST HDL_TAP TRUE
J 0
(-6150 2400);
DISPLAY 0.574468 (-6150 2400);
PAINT GREEN (-6150 2400);
DISPLAY INVISIBLE (-6150 2400);
FORCEPROP 1 LAST PATH I309
J 0
(-6477 2525);
DISPLAY 0.872340 (-6477 2525);
PAINT GREEN (-6477 2525);
DISPLAY INVISIBLE (-6477 2525);
FORCEADD TAP..6
(-6475 2325);
FORCEPROP 3 LASTPIN (-6425 2325) SIG_NAME GMI_CPU0_G1_CPU1_G3_TX_DP<7>
J 0
(-6415 2335);
DISPLAY 0.659574 (-6415 2335);
PAINT MONO (-6415 2335);
DISPLAY INVISIBLE (-6415 2335);
FORCEPROP 1 LASTPIN (-6425 2325) BN 7
J 0
(-6477 2333);
DISPLAY 0.489362 (-6477 2333);
PAINT MONO (-6477 2333);
FORCEPROP 2 LAST CDS_LIB standard
J 0
(-6475 2325);
DISPLAY INVISIBLE (-6475 2325);
FORCEPROP 1 LAST BODY_TYPE PLUMBING
J 0
(-6475 2275);
DISPLAY 0.574468 (-6475 2275);
PAINT GREEN (-6475 2275);
DISPLAY INVISIBLE (-6475 2275);
FORCEPROP 1 LAST HDL_TAP TRUE
J 0
(-6150 2200);
DISPLAY 0.574468 (-6150 2200);
PAINT GREEN (-6150 2200);
DISPLAY INVISIBLE (-6150 2200);
FORCEPROP 1 LAST PATH I310
J 0
(-6477 2325);
DISPLAY 0.872340 (-6477 2325);
PAINT GREEN (-6477 2325);
DISPLAY INVISIBLE (-6477 2325);
FORCEADD TAP..6
(-6475 2225);
FORCEPROP 3 LASTPIN (-6425 2225) SIG_NAME GMI_CPU0_G1_CPU1_G3_TX_DP<6>
J 0
(-6415 2235);
DISPLAY 0.659574 (-6415 2235);
PAINT MONO (-6415 2235);
DISPLAY INVISIBLE (-6415 2235);
FORCEPROP 1 LASTPIN (-6425 2225) BN 6
J 0
(-6477 2233);
DISPLAY 0.489362 (-6477 2233);
PAINT MONO (-6477 2233);
FORCEPROP 2 LAST CDS_LIB standard
J 0
(-6475 2225);
DISPLAY INVISIBLE (-6475 2225);
FORCEPROP 1 LAST BODY_TYPE PLUMBING
J 0
(-6475 2175);
DISPLAY 0.574468 (-6475 2175);
PAINT GREEN (-6475 2175);
DISPLAY INVISIBLE (-6475 2175);
FORCEPROP 1 LAST HDL_TAP TRUE
J 0
(-6150 2100);
DISPLAY 0.574468 (-6150 2100);
PAINT GREEN (-6150 2100);
DISPLAY INVISIBLE (-6150 2100);
FORCEPROP 1 LAST PATH I313
J 0
(-6477 2225);
DISPLAY 0.872340 (-6477 2225);
PAINT GREEN (-6477 2225);
DISPLAY INVISIBLE (-6477 2225);
FORCEADD TAP..6
(-6475 2125);
FORCEPROP 3 LASTPIN (-6425 2125) SIG_NAME GMI_CPU0_G1_CPU1_G3_TX_DP<5>
J 0
(-6415 2135);
DISPLAY 0.659574 (-6415 2135);
PAINT MONO (-6415 2135);
DISPLAY INVISIBLE (-6415 2135);
FORCEPROP 1 LASTPIN (-6425 2125) BN 5
J 0
(-6477 2133);
DISPLAY 0.489362 (-6477 2133);
PAINT MONO (-6477 2133);
FORCEPROP 2 LAST CDS_LIB standard
J 0
(-6475 2125);
DISPLAY INVISIBLE (-6475 2125);
FORCEPROP 1 LAST BODY_TYPE PLUMBING
J 0
(-6475 2075);
DISPLAY 0.574468 (-6475 2075);
PAINT GREEN (-6475 2075);
DISPLAY INVISIBLE (-6475 2075);
FORCEPROP 1 LAST HDL_TAP TRUE
J 0
(-6150 2000);
DISPLAY 0.574468 (-6150 2000);
PAINT GREEN (-6150 2000);
DISPLAY INVISIBLE (-6150 2000);
FORCEPROP 1 LAST PATH I314
J 0
(-6477 2125);
DISPLAY 0.872340 (-6477 2125);
PAINT GREEN (-6477 2125);
DISPLAY INVISIBLE (-6477 2125);
FORCEADD OFFPAGE..1
(-7575 3350);
FORCEPROP 2 LASTPIN (-7525 3350) SIG_NAME GMI_CPU0_G1_CPU1_G3_TX_DP<15:0>
J 0
(-7535 3360);
DISPLAY 0.489362 (-7535 3360);
FORCEPROP 2 LAST $XR0 22 
J 0
(-7826 3350);
DISPLAY 0.638298 (-7826 3350);
PAINT MONO (-7826 3350);
FORCEPROP 2 LAST CDS_LIB standard
J 0
(-7575 3350);
DISPLAY INVISIBLE (-7575 3350);
FORCEPROP 1 LAST OFFPAGE TRUE
J 0
(-7250 3225);
DISPLAY 0.872340 (-7250 3225);
PAINT GREEN (-7250 3225);
DISPLAY INVISIBLE (-7250 3225);
FORCEPROP 1 LAST COMMENT_BODY TRUE
J 0
(-7450 3250);
DISPLAY 0.872340 (-7450 3250);
PAINT GREEN (-7450 3250);
DISPLAY INVISIBLE (-7450 3250);
FORCEPROP 2 LAST PATH I318
J 0
(-7825 3400);
DISPLAY 1.021277 (-7825 3400);
DISPLAY INVISIBLE (-7825 3400);
FORCEADD TAP..6
(-6475 2025);
FORCEPROP 3 LASTPIN (-6425 2025) SIG_NAME GMI_CPU0_G1_CPU1_G3_TX_DP<4>
J 0
(-6415 2035);
DISPLAY 0.659574 (-6415 2035);
PAINT MONO (-6415 2035);
DISPLAY INVISIBLE (-6415 2035);
FORCEPROP 1 LASTPIN (-6425 2025) BN 4
J 0
(-6477 2033);
DISPLAY 0.489362 (-6477 2033);
PAINT MONO (-6477 2033);
FORCEPROP 2 LAST CDS_LIB standard
J 0
(-6475 2025);
DISPLAY INVISIBLE (-6475 2025);
FORCEPROP 1 LAST BODY_TYPE PLUMBING
J 0
(-6475 1975);
DISPLAY 0.574468 (-6475 1975);
PAINT GREEN (-6475 1975);
DISPLAY INVISIBLE (-6475 1975);
FORCEPROP 1 LAST HDL_TAP TRUE
J 0
(-6150 1900);
DISPLAY 0.574468 (-6150 1900);
PAINT GREEN (-6150 1900);
DISPLAY INVISIBLE (-6150 1900);
FORCEPROP 1 LAST PATH I320
J 0
(-6477 2025);
DISPLAY 0.872340 (-6477 2025);
PAINT GREEN (-6477 2025);
DISPLAY INVISIBLE (-6477 2025);
FORCEADD TAP..6
(-6475 1925);
FORCEPROP 3 LASTPIN (-6425 1925) SIG_NAME GMI_CPU0_G1_CPU1_G3_TX_DP<3>
J 0
(-6415 1935);
DISPLAY 0.659574 (-6415 1935);
PAINT MONO (-6415 1935);
DISPLAY INVISIBLE (-6415 1935);
FORCEPROP 1 LASTPIN (-6425 1925) BN 3
J 0
(-6477 1933);
DISPLAY 0.489362 (-6477 1933);
PAINT MONO (-6477 1933);
FORCEPROP 2 LAST CDS_LIB standard
J 0
(-6475 1925);
DISPLAY INVISIBLE (-6475 1925);
FORCEPROP 1 LAST BODY_TYPE PLUMBING
J 0
(-6475 1875);
DISPLAY 0.574468 (-6475 1875);
PAINT GREEN (-6475 1875);
DISPLAY INVISIBLE (-6475 1875);
FORCEPROP 1 LAST HDL_TAP TRUE
J 0
(-6150 1800);
DISPLAY 0.574468 (-6150 1800);
PAINT GREEN (-6150 1800);
DISPLAY INVISIBLE (-6150 1800);
FORCEPROP 1 LAST PATH I321
J 0
(-6477 1925);
DISPLAY 0.872340 (-6477 1925);
PAINT GREEN (-6477 1925);
DISPLAY INVISIBLE (-6477 1925);
FORCEADD TAP..6
(-6475 1825);
FORCEPROP 3 LASTPIN (-6425 1825) SIG_NAME GMI_CPU0_G1_CPU1_G3_TX_DP<2>
J 0
(-6415 1835);
DISPLAY 0.659574 (-6415 1835);
PAINT MONO (-6415 1835);
DISPLAY INVISIBLE (-6415 1835);
FORCEPROP 1 LASTPIN (-6425 1825) BN 2
J 0
(-6477 1833);
DISPLAY 0.489362 (-6477 1833);
PAINT MONO (-6477 1833);
FORCEPROP 2 LAST CDS_LIB standard
J 0
(-6475 1825);
DISPLAY INVISIBLE (-6475 1825);
FORCEPROP 1 LAST BODY_TYPE PLUMBING
J 0
(-6475 1775);
DISPLAY 0.574468 (-6475 1775);
PAINT GREEN (-6475 1775);
DISPLAY INVISIBLE (-6475 1775);
FORCEPROP 1 LAST HDL_TAP TRUE
J 0
(-6150 1700);
DISPLAY 0.574468 (-6150 1700);
PAINT GREEN (-6150 1700);
DISPLAY INVISIBLE (-6150 1700);
FORCEPROP 1 LAST PATH I322
J 0
(-6477 1825);
DISPLAY 0.872340 (-6477 1825);
PAINT GREEN (-6477 1825);
DISPLAY INVISIBLE (-6477 1825);
FORCEADD TAP..6
(-6475 1725);
FORCEPROP 3 LASTPIN (-6425 1725) SIG_NAME GMI_CPU0_G1_CPU1_G3_TX_DP<1>
J 0
(-6415 1735);
DISPLAY 0.659574 (-6415 1735);
PAINT MONO (-6415 1735);
DISPLAY INVISIBLE (-6415 1735);
FORCEPROP 1 LASTPIN (-6425 1725) BN 1
J 0
(-6477 1733);
DISPLAY 0.489362 (-6477 1733);
PAINT MONO (-6477 1733);
FORCEPROP 2 LAST CDS_LIB standard
J 0
(-6475 1725);
DISPLAY INVISIBLE (-6475 1725);
FORCEPROP 1 LAST BODY_TYPE PLUMBING
J 0
(-6475 1675);
DISPLAY 0.574468 (-6475 1675);
PAINT GREEN (-6475 1675);
DISPLAY INVISIBLE (-6475 1675);
FORCEPROP 1 LAST HDL_TAP TRUE
J 0
(-6150 1600);
DISPLAY 0.574468 (-6150 1600);
PAINT GREEN (-6150 1600);
DISPLAY INVISIBLE (-6150 1600);
FORCEPROP 1 LAST PATH I325
J 0
(-6477 1725);
DISPLAY 0.872340 (-6477 1725);
PAINT GREEN (-6477 1725);
DISPLAY INVISIBLE (-6477 1725);
FORCEADD TAP..6
(-6475 1625);
FORCEPROP 3 LASTPIN (-6425 1625) SIG_NAME GMI_CPU0_G1_CPU1_G3_TX_DP<0>
J 0
(-6415 1635);
DISPLAY 0.659574 (-6415 1635);
PAINT MONO (-6415 1635);
DISPLAY INVISIBLE (-6415 1635);
FORCEPROP 1 LASTPIN (-6425 1625) BN 0
J 0
(-6477 1633);
DISPLAY 0.489362 (-6477 1633);
PAINT MONO (-6477 1633);
FORCEPROP 2 LAST CDS_LIB standard
J 0
(-6475 1625);
DISPLAY INVISIBLE (-6475 1625);
FORCEPROP 1 LAST BODY_TYPE PLUMBING
J 0
(-6475 1575);
DISPLAY 0.574468 (-6475 1575);
PAINT GREEN (-6475 1575);
DISPLAY INVISIBLE (-6475 1575);
FORCEPROP 1 LAST HDL_TAP TRUE
J 0
(-6150 1500);
DISPLAY 0.574468 (-6150 1500);
PAINT GREEN (-6150 1500);
DISPLAY INVISIBLE (-6150 1500);
FORCEPROP 1 LAST PATH I327
J 0
(-6477 1625);
DISPLAY 0.872340 (-6477 1625);
PAINT GREEN (-6477 1625);
DISPLAY INVISIBLE (-6477 1625);
FORCEADD TAP..6
(-6650 5750);
FORCEPROP 3 LASTPIN (-6600 5750) SIG_NAME GMI_CPU0_G0_CPU1_G2_TX_DN<15>
J 0
(-6590 5760);
DISPLAY 0.659574 (-6590 5760);
PAINT MONO (-6590 5760);
DISPLAY INVISIBLE (-6590 5760);
FORCEPROP 1 LASTPIN (-6600 5750) BN 15
J 0
(-6652 5758);
DISPLAY 0.489362 (-6652 5758);
PAINT MONO (-6652 5758);
FORCEPROP 2 LAST CDS_LIB mstr_standard
J 0
(-6650 5750);
DISPLAY INVISIBLE (-6650 5750);
FORCEPROP 1 LAST BODY_TYPE PLUMBING
J 0
(-6650 5700);
DISPLAY 0.574468 (-6650 5700);
PAINT GREEN (-6650 5700);
DISPLAY INVISIBLE (-6650 5700);
FORCEPROP 1 LAST HDL_TAP TRUE
J 0
(-6325 5625);
DISPLAY 0.574468 (-6325 5625);
PAINT GREEN (-6325 5625);
DISPLAY INVISIBLE (-6325 5625);
FORCEPROP 1 LAST PATH I398
J 0
(-6652 5750);
DISPLAY 0.872340 (-6652 5750);
PAINT GREEN (-6652 5750);
DISPLAY INVISIBLE (-6652 5750);
FORCEADD TAP..6
(-6650 5650);
FORCEPROP 3 LASTPIN (-6600 5650) SIG_NAME GMI_CPU0_G0_CPU1_G2_TX_DN<14>
J 0
(-6590 5660);
DISPLAY 0.659574 (-6590 5660);
PAINT MONO (-6590 5660);
DISPLAY INVISIBLE (-6590 5660);
FORCEPROP 1 LASTPIN (-6600 5650) BN 14
J 0
(-6652 5658);
DISPLAY 0.489362 (-6652 5658);
PAINT MONO (-6652 5658);
FORCEPROP 2 LAST CDS_LIB mstr_standard
J 0
(-6650 5650);
DISPLAY INVISIBLE (-6650 5650);
FORCEPROP 1 LAST BODY_TYPE PLUMBING
J 0
(-6650 5600);
DISPLAY 0.574468 (-6650 5600);
PAINT GREEN (-6650 5600);
DISPLAY INVISIBLE (-6650 5600);
FORCEPROP 1 LAST HDL_TAP TRUE
J 0
(-6325 5525);
DISPLAY 0.574468 (-6325 5525);
PAINT GREEN (-6325 5525);
DISPLAY INVISIBLE (-6325 5525);
FORCEPROP 1 LAST PATH I399
J 0
(-6652 5650);
DISPLAY 0.872340 (-6652 5650);
PAINT GREEN (-6652 5650);
DISPLAY INVISIBLE (-6652 5650);
FORCEADD TAP..6
(-6650 5450);
FORCEPROP 3 LASTPIN (-6600 5450) SIG_NAME GMI_CPU0_G0_CPU1_G2_TX_DN<12>
J 0
(-6590 5460);
DISPLAY 0.659574 (-6590 5460);
PAINT MONO (-6590 5460);
DISPLAY INVISIBLE (-6590 5460);
FORCEPROP 1 LASTPIN (-6600 5450) BN 12
J 0
(-6652 5458);
DISPLAY 0.489362 (-6652 5458);
PAINT MONO (-6652 5458);
FORCEPROP 2 LAST CDS_LIB standard
J 0
(-6650 5450);
DISPLAY INVISIBLE (-6650 5450);
FORCEPROP 1 LAST BODY_TYPE PLUMBING
J 0
(-6650 5400);
DISPLAY 0.574468 (-6650 5400);
PAINT GREEN (-6650 5400);
DISPLAY INVISIBLE (-6650 5400);
FORCEPROP 1 LAST HDL_TAP TRUE
J 0
(-6325 5325);
DISPLAY 0.574468 (-6325 5325);
PAINT GREEN (-6325 5325);
DISPLAY INVISIBLE (-6325 5325);
FORCEPROP 1 LAST PATH I400
J 0
(-6652 5450);
DISPLAY 0.872340 (-6652 5450);
PAINT GREEN (-6652 5450);
DISPLAY INVISIBLE (-6652 5450);
FORCEADD TAP..6
(-6650 5550);
FORCEPROP 3 LASTPIN (-6600 5550) SIG_NAME GMI_CPU0_G0_CPU1_G2_TX_DN<13>
J 0
(-6590 5560);
DISPLAY 0.659574 (-6590 5560);
PAINT MONO (-6590 5560);
DISPLAY INVISIBLE (-6590 5560);
FORCEPROP 1 LASTPIN (-6600 5550) BN 13
J 0
(-6652 5558);
DISPLAY 0.489362 (-6652 5558);
PAINT MONO (-6652 5558);
FORCEPROP 2 LAST CDS_LIB standard
J 0
(-6650 5550);
DISPLAY INVISIBLE (-6650 5550);
FORCEPROP 1 LAST BODY_TYPE PLUMBING
J 0
(-6650 5500);
DISPLAY 0.574468 (-6650 5500);
PAINT GREEN (-6650 5500);
DISPLAY INVISIBLE (-6650 5500);
FORCEPROP 1 LAST HDL_TAP TRUE
J 0
(-6325 5425);
DISPLAY 0.574468 (-6325 5425);
PAINT GREEN (-6325 5425);
DISPLAY INVISIBLE (-6325 5425);
FORCEPROP 1 LAST PATH I401
J 0
(-6652 5550);
DISPLAY 0.872340 (-6652 5550);
PAINT GREEN (-6652 5550);
DISPLAY INVISIBLE (-6652 5550);
FORCEADD TAP..6
(-6650 5150);
FORCEPROP 3 LASTPIN (-6600 5150) SIG_NAME GMI_CPU0_G0_CPU1_G2_TX_DN<9>
J 0
(-6590 5160);
DISPLAY 0.659574 (-6590 5160);
PAINT MONO (-6590 5160);
DISPLAY INVISIBLE (-6590 5160);
FORCEPROP 1 LASTPIN (-6600 5150) BN 9
J 0
(-6652 5158);
DISPLAY 0.489362 (-6652 5158);
PAINT MONO (-6652 5158);
FORCEPROP 2 LAST CDS_LIB standard
J 0
(-6650 5150);
DISPLAY INVISIBLE (-6650 5150);
FORCEPROP 1 LAST BODY_TYPE PLUMBING
J 0
(-6650 5100);
DISPLAY 0.574468 (-6650 5100);
PAINT GREEN (-6650 5100);
DISPLAY INVISIBLE (-6650 5100);
FORCEPROP 1 LAST HDL_TAP TRUE
J 0
(-6325 5025);
DISPLAY 0.574468 (-6325 5025);
PAINT GREEN (-6325 5025);
DISPLAY INVISIBLE (-6325 5025);
FORCEPROP 1 LAST PATH I402
J 0
(-6652 5150);
DISPLAY 0.872340 (-6652 5150);
PAINT GREEN (-6652 5150);
DISPLAY INVISIBLE (-6652 5150);
FORCEADD TAP..6
(-6650 5350);
FORCEPROP 3 LASTPIN (-6600 5350) SIG_NAME GMI_CPU0_G0_CPU1_G2_TX_DN<11>
J 0
(-6590 5360);
DISPLAY 0.659574 (-6590 5360);
PAINT MONO (-6590 5360);
DISPLAY INVISIBLE (-6590 5360);
FORCEPROP 1 LASTPIN (-6600 5350) BN 11
J 0
(-6652 5358);
DISPLAY 0.489362 (-6652 5358);
PAINT MONO (-6652 5358);
FORCEPROP 2 LAST CDS_LIB standard
J 0
(-6650 5350);
DISPLAY INVISIBLE (-6650 5350);
FORCEPROP 1 LAST BODY_TYPE PLUMBING
J 0
(-6650 5300);
DISPLAY 0.574468 (-6650 5300);
PAINT GREEN (-6650 5300);
DISPLAY INVISIBLE (-6650 5300);
FORCEPROP 1 LAST HDL_TAP TRUE
J 0
(-6325 5225);
DISPLAY 0.574468 (-6325 5225);
PAINT GREEN (-6325 5225);
DISPLAY INVISIBLE (-6325 5225);
FORCEPROP 1 LAST PATH I403
J 0
(-6652 5350);
DISPLAY 0.872340 (-6652 5350);
PAINT GREEN (-6652 5350);
DISPLAY INVISIBLE (-6652 5350);
FORCEADD TAP..6
(-6650 5250);
FORCEPROP 3 LASTPIN (-6600 5250) SIG_NAME GMI_CPU0_G0_CPU1_G2_TX_DN<10>
J 0
(-6590 5260);
DISPLAY 0.659574 (-6590 5260);
PAINT MONO (-6590 5260);
DISPLAY INVISIBLE (-6590 5260);
FORCEPROP 1 LASTPIN (-6600 5250) BN 10
J 0
(-6652 5258);
DISPLAY 0.489362 (-6652 5258);
PAINT MONO (-6652 5258);
FORCEPROP 2 LAST CDS_LIB standard
J 0
(-6650 5250);
DISPLAY INVISIBLE (-6650 5250);
FORCEPROP 1 LAST BODY_TYPE PLUMBING
J 0
(-6650 5200);
DISPLAY 0.574468 (-6650 5200);
PAINT GREEN (-6650 5200);
DISPLAY INVISIBLE (-6650 5200);
FORCEPROP 1 LAST HDL_TAP TRUE
J 0
(-6325 5125);
DISPLAY 0.574468 (-6325 5125);
PAINT GREEN (-6325 5125);
DISPLAY INVISIBLE (-6325 5125);
FORCEPROP 1 LAST PATH I404
J 0
(-6652 5250);
DISPLAY 0.872340 (-6652 5250);
PAINT GREEN (-6652 5250);
DISPLAY INVISIBLE (-6652 5250);
FORCEADD TAP..6
(-6650 4950);
FORCEPROP 3 LASTPIN (-6600 4950) SIG_NAME GMI_CPU0_G0_CPU1_G2_TX_DN<7>
J 0
(-6590 4960);
DISPLAY 0.659574 (-6590 4960);
PAINT MONO (-6590 4960);
DISPLAY INVISIBLE (-6590 4960);
FORCEPROP 1 LASTPIN (-6600 4950) BN 7
J 0
(-6652 4958);
DISPLAY 0.489362 (-6652 4958);
PAINT MONO (-6652 4958);
FORCEPROP 2 LAST CDS_LIB standard
J 0
(-6650 4950);
DISPLAY INVISIBLE (-6650 4950);
FORCEPROP 1 LAST BODY_TYPE PLUMBING
J 0
(-6650 4900);
DISPLAY 0.574468 (-6650 4900);
PAINT GREEN (-6650 4900);
DISPLAY INVISIBLE (-6650 4900);
FORCEPROP 1 LAST HDL_TAP TRUE
J 0
(-6325 4825);
DISPLAY 0.574468 (-6325 4825);
PAINT GREEN (-6325 4825);
DISPLAY INVISIBLE (-6325 4825);
FORCEPROP 1 LAST PATH I405
J 0
(-6652 4950);
DISPLAY 0.872340 (-6652 4950);
PAINT GREEN (-6652 4950);
DISPLAY INVISIBLE (-6652 4950);
FORCEADD TAP..6
(-6650 5050);
FORCEPROP 3 LASTPIN (-6600 5050) SIG_NAME GMI_CPU0_G0_CPU1_G2_TX_DN<8>
J 0
(-6590 5060);
DISPLAY 0.659574 (-6590 5060);
PAINT MONO (-6590 5060);
DISPLAY INVISIBLE (-6590 5060);
FORCEPROP 1 LASTPIN (-6600 5050) BN 8
J 0
(-6652 5058);
DISPLAY 0.489362 (-6652 5058);
PAINT MONO (-6652 5058);
FORCEPROP 2 LAST CDS_LIB standard
J 0
(-6650 5050);
DISPLAY INVISIBLE (-6650 5050);
FORCEPROP 1 LAST BODY_TYPE PLUMBING
J 0
(-6650 5000);
DISPLAY 0.574468 (-6650 5000);
PAINT GREEN (-6650 5000);
DISPLAY INVISIBLE (-6650 5000);
FORCEPROP 1 LAST HDL_TAP TRUE
J 0
(-6325 4925);
DISPLAY 0.574468 (-6325 4925);
PAINT GREEN (-6325 4925);
DISPLAY INVISIBLE (-6325 4925);
FORCEPROP 1 LAST PATH I406
J 0
(-6652 5050);
DISPLAY 0.872340 (-6652 5050);
PAINT GREEN (-6652 5050);
DISPLAY INVISIBLE (-6652 5050);
FORCEADD TAP..6
(-6650 4850);
FORCEPROP 3 LASTPIN (-6600 4850) SIG_NAME GMI_CPU0_G0_CPU1_G2_TX_DN<6>
J 0
(-6590 4860);
DISPLAY 0.659574 (-6590 4860);
PAINT MONO (-6590 4860);
DISPLAY INVISIBLE (-6590 4860);
FORCEPROP 1 LASTPIN (-6600 4850) BN 6
J 0
(-6652 4858);
DISPLAY 0.489362 (-6652 4858);
PAINT MONO (-6652 4858);
FORCEPROP 2 LAST CDS_LIB standard
J 0
(-6650 4850);
DISPLAY INVISIBLE (-6650 4850);
FORCEPROP 1 LAST BODY_TYPE PLUMBING
J 0
(-6650 4800);
DISPLAY 0.574468 (-6650 4800);
PAINT GREEN (-6650 4800);
DISPLAY INVISIBLE (-6650 4800);
FORCEPROP 1 LAST HDL_TAP TRUE
J 0
(-6325 4725);
DISPLAY 0.574468 (-6325 4725);
PAINT GREEN (-6325 4725);
DISPLAY INVISIBLE (-6325 4725);
FORCEPROP 1 LAST PATH I407
J 0
(-6652 4850);
DISPLAY 0.872340 (-6652 4850);
PAINT GREEN (-6652 4850);
DISPLAY INVISIBLE (-6652 4850);
FORCEADD TAP..6
(-6650 4650);
FORCEPROP 3 LASTPIN (-6600 4650) SIG_NAME GMI_CPU0_G0_CPU1_G2_TX_DN<4>
J 0
(-6590 4660);
DISPLAY 0.659574 (-6590 4660);
PAINT MONO (-6590 4660);
DISPLAY INVISIBLE (-6590 4660);
FORCEPROP 1 LASTPIN (-6600 4650) BN 4
J 0
(-6652 4658);
DISPLAY 0.489362 (-6652 4658);
PAINT MONO (-6652 4658);
FORCEPROP 2 LAST CDS_LIB standard
J 0
(-6650 4650);
DISPLAY INVISIBLE (-6650 4650);
FORCEPROP 1 LAST BODY_TYPE PLUMBING
J 0
(-6650 4600);
DISPLAY 0.574468 (-6650 4600);
PAINT GREEN (-6650 4600);
DISPLAY INVISIBLE (-6650 4600);
FORCEPROP 1 LAST HDL_TAP TRUE
J 0
(-6325 4525);
DISPLAY 0.574468 (-6325 4525);
PAINT GREEN (-6325 4525);
DISPLAY INVISIBLE (-6325 4525);
FORCEPROP 1 LAST PATH I408
J 0
(-6652 4650);
DISPLAY 0.872340 (-6652 4650);
PAINT GREEN (-6652 4650);
DISPLAY INVISIBLE (-6652 4650);
FORCEADD TAP..6
(-6650 4750);
FORCEPROP 3 LASTPIN (-6600 4750) SIG_NAME GMI_CPU0_G0_CPU1_G2_TX_DN<5>
J 0
(-6590 4760);
DISPLAY 0.659574 (-6590 4760);
PAINT MONO (-6590 4760);
DISPLAY INVISIBLE (-6590 4760);
FORCEPROP 1 LASTPIN (-6600 4750) BN 5
J 0
(-6652 4758);
DISPLAY 0.489362 (-6652 4758);
PAINT MONO (-6652 4758);
FORCEPROP 2 LAST CDS_LIB standard
J 0
(-6650 4750);
DISPLAY INVISIBLE (-6650 4750);
FORCEPROP 1 LAST BODY_TYPE PLUMBING
J 0
(-6650 4700);
DISPLAY 0.574468 (-6650 4700);
PAINT GREEN (-6650 4700);
DISPLAY INVISIBLE (-6650 4700);
FORCEPROP 1 LAST HDL_TAP TRUE
J 0
(-6325 4625);
DISPLAY 0.574468 (-6325 4625);
PAINT GREEN (-6325 4625);
DISPLAY INVISIBLE (-6325 4625);
FORCEPROP 1 LAST PATH I409
J 0
(-6652 4750);
DISPLAY 0.872340 (-6652 4750);
PAINT GREEN (-6652 4750);
DISPLAY INVISIBLE (-6652 4750);
FORCEADD TAP..6
(-6650 4450);
FORCEPROP 3 LASTPIN (-6600 4450) SIG_NAME GMI_CPU0_G0_CPU1_G2_TX_DN<2>
J 0
(-6590 4460);
DISPLAY 0.659574 (-6590 4460);
PAINT MONO (-6590 4460);
DISPLAY INVISIBLE (-6590 4460);
FORCEPROP 1 LASTPIN (-6600 4450) BN 2
J 0
(-6652 4458);
DISPLAY 0.489362 (-6652 4458);
PAINT MONO (-6652 4458);
FORCEPROP 2 LAST CDS_LIB standard
J 0
(-6650 4450);
DISPLAY INVISIBLE (-6650 4450);
FORCEPROP 1 LAST BODY_TYPE PLUMBING
J 0
(-6650 4400);
DISPLAY 0.574468 (-6650 4400);
PAINT GREEN (-6650 4400);
DISPLAY INVISIBLE (-6650 4400);
FORCEPROP 1 LAST HDL_TAP TRUE
J 0
(-6325 4325);
DISPLAY 0.574468 (-6325 4325);
PAINT GREEN (-6325 4325);
DISPLAY INVISIBLE (-6325 4325);
FORCEPROP 1 LAST PATH I410
J 0
(-6652 4450);
DISPLAY 0.872340 (-6652 4450);
PAINT GREEN (-6652 4450);
DISPLAY INVISIBLE (-6652 4450);
FORCEADD TAP..6
(-6650 4550);
FORCEPROP 3 LASTPIN (-6600 4550) SIG_NAME GMI_CPU0_G0_CPU1_G2_TX_DN<3>
J 0
(-6590 4560);
DISPLAY 0.659574 (-6590 4560);
PAINT MONO (-6590 4560);
DISPLAY INVISIBLE (-6590 4560);
FORCEPROP 1 LASTPIN (-6600 4550) BN 3
J 0
(-6652 4558);
DISPLAY 0.489362 (-6652 4558);
PAINT MONO (-6652 4558);
FORCEPROP 2 LAST CDS_LIB standard
J 0
(-6650 4550);
DISPLAY INVISIBLE (-6650 4550);
FORCEPROP 1 LAST BODY_TYPE PLUMBING
J 0
(-6650 4500);
DISPLAY 0.574468 (-6650 4500);
PAINT GREEN (-6650 4500);
DISPLAY INVISIBLE (-6650 4500);
FORCEPROP 1 LAST HDL_TAP TRUE
J 0
(-6325 4425);
DISPLAY 0.574468 (-6325 4425);
PAINT GREEN (-6325 4425);
DISPLAY INVISIBLE (-6325 4425);
FORCEPROP 1 LAST PATH I411
J 0
(-6652 4550);
DISPLAY 0.872340 (-6652 4550);
PAINT GREEN (-6652 4550);
DISPLAY INVISIBLE (-6652 4550);
FORCEADD TAP..6
(-6650 4350);
FORCEPROP 3 LASTPIN (-6600 4350) SIG_NAME GMI_CPU0_G0_CPU1_G2_TX_DN<1>
J 0
(-6590 4360);
DISPLAY 0.659574 (-6590 4360);
PAINT MONO (-6590 4360);
DISPLAY INVISIBLE (-6590 4360);
FORCEPROP 1 LASTPIN (-6600 4350) BN 1
J 0
(-6652 4358);
DISPLAY 0.489362 (-6652 4358);
PAINT MONO (-6652 4358);
FORCEPROP 2 LAST CDS_LIB standard
J 0
(-6650 4350);
DISPLAY INVISIBLE (-6650 4350);
FORCEPROP 1 LAST BODY_TYPE PLUMBING
J 0
(-6650 4300);
DISPLAY 0.574468 (-6650 4300);
PAINT GREEN (-6650 4300);
DISPLAY INVISIBLE (-6650 4300);
FORCEPROP 1 LAST HDL_TAP TRUE
J 0
(-6325 4225);
DISPLAY 0.574468 (-6325 4225);
PAINT GREEN (-6325 4225);
DISPLAY INVISIBLE (-6325 4225);
FORCEPROP 1 LAST PATH I412
J 0
(-6652 4350);
DISPLAY 0.872340 (-6652 4350);
PAINT GREEN (-6652 4350);
DISPLAY INVISIBLE (-6652 4350);
FORCEADD TAP..6
(-6650 4250);
FORCEPROP 3 LASTPIN (-6600 4250) SIG_NAME GMI_CPU0_G0_CPU1_G2_TX_DN<0>
J 0
(-6590 4260);
DISPLAY 0.659574 (-6590 4260);
PAINT MONO (-6590 4260);
DISPLAY INVISIBLE (-6590 4260);
FORCEPROP 1 LASTPIN (-6600 4250) BN 0
J 0
(-6652 4258);
DISPLAY 0.489362 (-6652 4258);
PAINT MONO (-6652 4258);
FORCEPROP 2 LAST CDS_LIB standard
J 0
(-6650 4250);
DISPLAY INVISIBLE (-6650 4250);
FORCEPROP 1 LAST BODY_TYPE PLUMBING
J 0
(-6650 4200);
DISPLAY 0.574468 (-6650 4200);
PAINT GREEN (-6650 4200);
DISPLAY INVISIBLE (-6650 4200);
FORCEPROP 1 LAST HDL_TAP TRUE
J 0
(-6325 4125);
DISPLAY 0.574468 (-6325 4125);
PAINT GREEN (-6325 4125);
DISPLAY INVISIBLE (-6325 4125);
FORCEPROP 1 LAST PATH I413
J 0
(-6652 4250);
DISPLAY 0.872340 (-6652 4250);
PAINT GREEN (-6652 4250);
DISPLAY INVISIBLE (-6652 4250);
FORCEADD OFFPAGE..1
(-7700 5975);
FORCEPROP 2 LAST $XR0 22 
J 0
(-7951 5975);
DISPLAY 0.638298 (-7951 5975);
PAINT MONO (-7951 5975);
FORCEPROP 2 LAST CDS_LIB standard
J 0
(-7700 5975);
DISPLAY INVISIBLE (-7700 5975);
FORCEPROP 1 LAST OFFPAGE TRUE
J 0
(-7375 5850);
DISPLAY 0.872340 (-7375 5850);
PAINT GREEN (-7375 5850);
DISPLAY INVISIBLE (-7375 5850);
FORCEPROP 1 LAST COMMENT_BODY TRUE
J 0
(-7575 5875);
DISPLAY 0.872340 (-7575 5875);
PAINT GREEN (-7575 5875);
DISPLAY INVISIBLE (-7575 5875);
FORCEPROP 2 LAST PATH I414
J 0
(-7950 6025);
DISPLAY 1.021277 (-7950 6025);
DISPLAY INVISIBLE (-7950 6025);
FORCEADD OFFPAGE..2
(-1800 5975);
FORCEPROP 2 LAST $XR0 22 
J 0
(-1611 5975);
DISPLAY 0.638298 (-1611 5975);
PAINT MONO (-1611 5975);
FORCEPROP 2 LAST CDS_LIB standard
J 0
(-1800 5975);
DISPLAY INVISIBLE (-1800 5975);
FORCEPROP 1 LAST OFFPAGE TRUE
J 0
(-1475 5850);
DISPLAY 0.872340 (-1475 5850);
PAINT GREEN (-1475 5850);
DISPLAY INVISIBLE (-1475 5850);
FORCEPROP 1 LAST COMMENT_BODY TRUE
J 0
(-1845 5880);
DISPLAY 0.872340 (-1845 5880);
PAINT GREEN (-1845 5880);
DISPLAY INVISIBLE (-1845 5880);
FORCEPROP 2 LAST PATH I415
J 0
(-1600 6025);
DISPLAY 1.021277 (-1600 6025);
DISPLAY INVISIBLE (-1600 6025);
FORCEADD TAP..6
R 2
(-2925 5750);
FORCEPROP 3 LASTPIN (-2975 5750) SIG_NAME GMI_CPU1_G2_CPU0_G0_TX_DN<15>
J 0
(-2965 5760);
DISPLAY 0.659574 (-2965 5760);
PAINT MONO (-2965 5760);
DISPLAY INVISIBLE (-2965 5760);
FORCEPROP 1 LASTPIN (-2975 5750) BN 15
J 2
(-2923 5758);
DISPLAY 0.489362 (-2923 5758);
PAINT MONO (-2923 5758);
FORCEPROP 2 LAST CDS_LIB mstr_standard
J 0
(-2925 5750);
DISPLAY INVISIBLE (-2925 5750);
FORCEPROP 2 LAST BOM_COST IO_SLOT
J 0
(-3425 5850);
DISPLAY 0.829787 (-3425 5850);
DISPLAY INVISIBLE (-3425 5850);
FORCEPROP 2 LAST ROOM RISER1
J 0
(-3425 5800);
DISPLAY 0.829787 (-3425 5800);
PAINT RED (-3425 5800);
DISPLAY INVISIBLE (-3425 5800);
FORCEPROP 1 LAST BODY_TYPE PLUMBING
J 2
(-2925 5700);
DISPLAY 0.702128 (-2925 5700);
PAINT GREEN (-2925 5700);
DISPLAY INVISIBLE (-2925 5700);
FORCEPROP 1 LAST HDL_TAP TRUE
J 2
(-3250 5625);
DISPLAY 0.702128 (-3250 5625);
PAINT GREEN (-3250 5625);
DISPLAY INVISIBLE (-3250 5625);
FORCEPROP 1 LAST PATH I416
J 2
(-2923 5750);
DISPLAY 0.872340 (-2923 5750);
PAINT GREEN (-2923 5750);
DISPLAY INVISIBLE (-2923 5750);
FORCEADD TAP..6
R 2
(-2925 5650);
FORCEPROP 3 LASTPIN (-2975 5650) SIG_NAME GMI_CPU1_G2_CPU0_G0_TX_DN<14>
J 0
(-2965 5660);
DISPLAY 0.659574 (-2965 5660);
PAINT MONO (-2965 5660);
DISPLAY INVISIBLE (-2965 5660);
FORCEPROP 1 LASTPIN (-2975 5650) BN 14
J 2
(-2923 5658);
DISPLAY 0.489362 (-2923 5658);
PAINT MONO (-2923 5658);
FORCEPROP 2 LAST BOM_COST IO_SLOT
J 0
(-3425 5750);
DISPLAY 0.829787 (-3425 5750);
DISPLAY INVISIBLE (-3425 5750);
FORCEPROP 2 LAST CDS_LIB mstr_standard
J 0
(-2925 5650);
DISPLAY INVISIBLE (-2925 5650);
FORCEPROP 2 LAST ROOM RISER1
J 0
(-3425 5700);
DISPLAY 0.829787 (-3425 5700);
PAINT RED (-3425 5700);
DISPLAY INVISIBLE (-3425 5700);
FORCEPROP 1 LAST BODY_TYPE PLUMBING
J 2
(-2925 5600);
DISPLAY 0.702128 (-2925 5600);
PAINT GREEN (-2925 5600);
DISPLAY INVISIBLE (-2925 5600);
FORCEPROP 1 LAST HDL_TAP TRUE
J 2
(-3250 5525);
DISPLAY 0.702128 (-3250 5525);
PAINT GREEN (-3250 5525);
DISPLAY INVISIBLE (-3250 5525);
FORCEPROP 1 LAST PATH I417
J 2
(-2923 5650);
DISPLAY 0.872340 (-2923 5650);
PAINT GREEN (-2923 5650);
DISPLAY INVISIBLE (-2923 5650);
FORCEADD TAP..6
R 2
(-2925 5250);
FORCEPROP 3 LASTPIN (-2975 5250) SIG_NAME GMI_CPU1_G2_CPU0_G0_TX_DN<10>
J 0
(-2965 5260);
DISPLAY 0.659574 (-2965 5260);
PAINT MONO (-2965 5260);
DISPLAY INVISIBLE (-2965 5260);
FORCEPROP 1 LASTPIN (-2975 5250) BN 10
J 2
(-2923 5258);
DISPLAY 0.489362 (-2923 5258);
PAINT MONO (-2923 5258);
FORCEPROP 2 LAST BOM_COST IO_SLOT
J 0
(-3425 5350);
DISPLAY 0.829787 (-3425 5350);
DISPLAY INVISIBLE (-3425 5350);
FORCEPROP 2 LAST CDS_LIB standard
J 0
(-2925 5250);
DISPLAY INVISIBLE (-2925 5250);
FORCEPROP 2 LAST ROOM RISER1
J 0
(-3425 5300);
DISPLAY 0.829787 (-3425 5300);
PAINT RED (-3425 5300);
DISPLAY INVISIBLE (-3425 5300);
FORCEPROP 1 LAST BODY_TYPE PLUMBING
J 2
(-2925 5200);
DISPLAY 0.702128 (-2925 5200);
PAINT GREEN (-2925 5200);
DISPLAY INVISIBLE (-2925 5200);
FORCEPROP 1 LAST HDL_TAP TRUE
J 2
(-3250 5125);
DISPLAY 0.702128 (-3250 5125);
PAINT GREEN (-3250 5125);
DISPLAY INVISIBLE (-3250 5125);
FORCEPROP 1 LAST PATH I418
J 2
(-2923 5250);
DISPLAY 0.872340 (-2923 5250);
PAINT GREEN (-2923 5250);
DISPLAY INVISIBLE (-2923 5250);
FORCEADD TAP..6
R 2
(-2925 5150);
FORCEPROP 3 LASTPIN (-2975 5150) SIG_NAME GMI_CPU1_G2_CPU0_G0_TX_DN<9>
J 0
(-2965 5160);
DISPLAY 0.659574 (-2965 5160);
PAINT MONO (-2965 5160);
DISPLAY INVISIBLE (-2965 5160);
FORCEPROP 1 LASTPIN (-2975 5150) BN 9
J 2
(-2923 5158);
DISPLAY 0.489362 (-2923 5158);
PAINT MONO (-2923 5158);
FORCEPROP 2 LAST BOM_COST IO_SLOT
J 0
(-3425 5250);
DISPLAY 0.829787 (-3425 5250);
DISPLAY INVISIBLE (-3425 5250);
FORCEPROP 2 LAST CDS_LIB standard
J 0
(-2925 5150);
DISPLAY INVISIBLE (-2925 5150);
FORCEPROP 2 LAST ROOM RISER1
J 0
(-3425 5200);
DISPLAY 0.829787 (-3425 5200);
PAINT RED (-3425 5200);
DISPLAY INVISIBLE (-3425 5200);
FORCEPROP 1 LAST BODY_TYPE PLUMBING
J 2
(-2925 5100);
DISPLAY 0.702128 (-2925 5100);
PAINT GREEN (-2925 5100);
DISPLAY INVISIBLE (-2925 5100);
FORCEPROP 1 LAST HDL_TAP TRUE
J 2
(-3250 5025);
DISPLAY 0.702128 (-3250 5025);
PAINT GREEN (-3250 5025);
DISPLAY INVISIBLE (-3250 5025);
FORCEPROP 1 LAST PATH I419
J 2
(-2923 5150);
DISPLAY 0.872340 (-2923 5150);
PAINT GREEN (-2923 5150);
DISPLAY INVISIBLE (-2923 5150);
FORCEADD TAP..6
R 2
(-2925 5350);
FORCEPROP 3 LASTPIN (-2975 5350) SIG_NAME GMI_CPU1_G2_CPU0_G0_TX_DN<11>
J 0
(-2965 5360);
DISPLAY 0.659574 (-2965 5360);
PAINT MONO (-2965 5360);
DISPLAY INVISIBLE (-2965 5360);
FORCEPROP 1 LASTPIN (-2975 5350) BN 11
J 2
(-2923 5358);
DISPLAY 0.489362 (-2923 5358);
PAINT MONO (-2923 5358);
FORCEPROP 2 LAST BOM_COST IO_SLOT
J 0
(-3425 5450);
DISPLAY 0.829787 (-3425 5450);
DISPLAY INVISIBLE (-3425 5450);
FORCEPROP 2 LAST CDS_LIB standard
J 0
(-2925 5350);
DISPLAY INVISIBLE (-2925 5350);
FORCEPROP 2 LAST ROOM RISER1
J 0
(-3425 5400);
DISPLAY 0.829787 (-3425 5400);
PAINT RED (-3425 5400);
DISPLAY INVISIBLE (-3425 5400);
FORCEPROP 1 LAST BODY_TYPE PLUMBING
J 2
(-2925 5300);
DISPLAY 0.702128 (-2925 5300);
PAINT GREEN (-2925 5300);
DISPLAY INVISIBLE (-2925 5300);
FORCEPROP 1 LAST HDL_TAP TRUE
J 2
(-3250 5225);
DISPLAY 0.702128 (-3250 5225);
PAINT GREEN (-3250 5225);
DISPLAY INVISIBLE (-3250 5225);
FORCEPROP 1 LAST PATH I420
J 2
(-2923 5350);
DISPLAY 0.872340 (-2923 5350);
PAINT GREEN (-2923 5350);
DISPLAY INVISIBLE (-2923 5350);
FORCEADD TAP..6
R 2
(-2925 5450);
FORCEPROP 3 LASTPIN (-2975 5450) SIG_NAME GMI_CPU1_G2_CPU0_G0_TX_DN<12>
J 0
(-2965 5460);
DISPLAY 0.659574 (-2965 5460);
PAINT MONO (-2965 5460);
DISPLAY INVISIBLE (-2965 5460);
FORCEPROP 1 LASTPIN (-2975 5450) BN 12
J 2
(-2923 5458);
DISPLAY 0.489362 (-2923 5458);
PAINT MONO (-2923 5458);
FORCEPROP 2 LAST BOM_COST IO_SLOT
J 0
(-3425 5550);
DISPLAY 0.829787 (-3425 5550);
DISPLAY INVISIBLE (-3425 5550);
FORCEPROP 2 LAST CDS_LIB standard
J 0
(-2925 5450);
DISPLAY INVISIBLE (-2925 5450);
FORCEPROP 2 LAST ROOM RISER1
J 0
(-3425 5500);
DISPLAY 0.829787 (-3425 5500);
PAINT RED (-3425 5500);
DISPLAY INVISIBLE (-3425 5500);
FORCEPROP 1 LAST BODY_TYPE PLUMBING
J 2
(-2925 5400);
DISPLAY 0.702128 (-2925 5400);
PAINT GREEN (-2925 5400);
DISPLAY INVISIBLE (-2925 5400);
FORCEPROP 1 LAST HDL_TAP TRUE
J 2
(-3250 5325);
DISPLAY 0.702128 (-3250 5325);
PAINT GREEN (-3250 5325);
DISPLAY INVISIBLE (-3250 5325);
FORCEPROP 1 LAST PATH I421
J 2
(-2923 5450);
DISPLAY 0.872340 (-2923 5450);
PAINT GREEN (-2923 5450);
DISPLAY INVISIBLE (-2923 5450);
FORCEADD TAP..6
R 2
(-2925 5550);
FORCEPROP 3 LASTPIN (-2975 5550) SIG_NAME GMI_CPU1_G2_CPU0_G0_TX_DN<13>
J 0
(-2965 5560);
DISPLAY 0.659574 (-2965 5560);
PAINT MONO (-2965 5560);
DISPLAY INVISIBLE (-2965 5560);
FORCEPROP 1 LASTPIN (-2975 5550) BN 13
J 2
(-2923 5558);
DISPLAY 0.489362 (-2923 5558);
PAINT MONO (-2923 5558);
FORCEPROP 2 LAST BOM_COST IO_SLOT
J 0
(-3425 5650);
DISPLAY 0.829787 (-3425 5650);
DISPLAY INVISIBLE (-3425 5650);
FORCEPROP 2 LAST CDS_LIB standard
J 0
(-2925 5550);
DISPLAY INVISIBLE (-2925 5550);
FORCEPROP 2 LAST ROOM RISER1
J 0
(-3425 5600);
DISPLAY 0.829787 (-3425 5600);
PAINT RED (-3425 5600);
DISPLAY INVISIBLE (-3425 5600);
FORCEPROP 1 LAST BODY_TYPE PLUMBING
J 2
(-2925 5500);
DISPLAY 0.702128 (-2925 5500);
PAINT GREEN (-2925 5500);
DISPLAY INVISIBLE (-2925 5500);
FORCEPROP 1 LAST HDL_TAP TRUE
J 2
(-3250 5425);
DISPLAY 0.702128 (-3250 5425);
PAINT GREEN (-3250 5425);
DISPLAY INVISIBLE (-3250 5425);
FORCEPROP 1 LAST PATH I422
J 2
(-2923 5550);
DISPLAY 0.872340 (-2923 5550);
PAINT GREEN (-2923 5550);
DISPLAY INVISIBLE (-2923 5550);
FORCEADD TAP..6
R 2
(-2925 4850);
FORCEPROP 3 LASTPIN (-2975 4850) SIG_NAME GMI_CPU1_G2_CPU0_G0_TX_DN<6>
J 0
(-2965 4860);
DISPLAY 0.659574 (-2965 4860);
PAINT MONO (-2965 4860);
DISPLAY INVISIBLE (-2965 4860);
FORCEPROP 1 LASTPIN (-2975 4850) BN 6
J 2
(-2923 4858);
DISPLAY 0.489362 (-2923 4858);
PAINT MONO (-2923 4858);
FORCEPROP 2 LAST BOM_COST IO_SLOT
J 0
(-3425 4950);
DISPLAY 0.829787 (-3425 4950);
DISPLAY INVISIBLE (-3425 4950);
FORCEPROP 2 LAST CDS_LIB standard
J 0
(-2925 4850);
DISPLAY INVISIBLE (-2925 4850);
FORCEPROP 2 LAST ROOM RISER1
J 0
(-3425 4900);
DISPLAY 0.829787 (-3425 4900);
PAINT RED (-3425 4900);
DISPLAY INVISIBLE (-3425 4900);
FORCEPROP 1 LAST BODY_TYPE PLUMBING
J 2
(-2925 4800);
DISPLAY 0.702128 (-2925 4800);
PAINT GREEN (-2925 4800);
DISPLAY INVISIBLE (-2925 4800);
FORCEPROP 1 LAST HDL_TAP TRUE
J 2
(-3250 4725);
DISPLAY 0.702128 (-3250 4725);
PAINT GREEN (-3250 4725);
DISPLAY INVISIBLE (-3250 4725);
FORCEPROP 1 LAST PATH I423
J 2
(-2923 4850);
DISPLAY 0.872340 (-2923 4850);
PAINT GREEN (-2923 4850);
DISPLAY INVISIBLE (-2923 4850);
FORCEADD TAP..6
R 2
(-2925 4650);
FORCEPROP 3 LASTPIN (-2975 4650) SIG_NAME GMI_CPU1_G2_CPU0_G0_TX_DN<4>
J 0
(-2965 4660);
DISPLAY 0.659574 (-2965 4660);
PAINT MONO (-2965 4660);
DISPLAY INVISIBLE (-2965 4660);
FORCEPROP 1 LASTPIN (-2975 4650) BN 4
J 2
(-2923 4658);
DISPLAY 0.489362 (-2923 4658);
PAINT MONO (-2923 4658);
FORCEPROP 2 LAST BOM_COST IO_SLOT
J 0
(-3425 4750);
DISPLAY 0.829787 (-3425 4750);
DISPLAY INVISIBLE (-3425 4750);
FORCEPROP 2 LAST CDS_LIB standard
J 0
(-2925 4650);
DISPLAY INVISIBLE (-2925 4650);
FORCEPROP 2 LAST ROOM RISER1
J 0
(-3425 4700);
DISPLAY 0.829787 (-3425 4700);
PAINT RED (-3425 4700);
DISPLAY INVISIBLE (-3425 4700);
FORCEPROP 1 LAST BODY_TYPE PLUMBING
J 2
(-2925 4600);
DISPLAY 0.702128 (-2925 4600);
PAINT GREEN (-2925 4600);
DISPLAY INVISIBLE (-2925 4600);
FORCEPROP 1 LAST HDL_TAP TRUE
J 2
(-3250 4525);
DISPLAY 0.702128 (-3250 4525);
PAINT GREEN (-3250 4525);
DISPLAY INVISIBLE (-3250 4525);
FORCEPROP 1 LAST PATH I424
J 2
(-2923 4650);
DISPLAY 0.872340 (-2923 4650);
PAINT GREEN (-2923 4650);
DISPLAY INVISIBLE (-2923 4650);
FORCEADD TAP..6
R 2
(-2925 4750);
FORCEPROP 3 LASTPIN (-2975 4750) SIG_NAME GMI_CPU1_G2_CPU0_G0_TX_DN<5>
J 0
(-2965 4760);
DISPLAY 0.659574 (-2965 4760);
PAINT MONO (-2965 4760);
DISPLAY INVISIBLE (-2965 4760);
FORCEPROP 1 LASTPIN (-2975 4750) BN 5
J 2
(-2923 4758);
DISPLAY 0.489362 (-2923 4758);
PAINT MONO (-2923 4758);
FORCEPROP 2 LAST BOM_COST IO_SLOT
J 0
(-3425 4850);
DISPLAY 0.829787 (-3425 4850);
DISPLAY INVISIBLE (-3425 4850);
FORCEPROP 2 LAST CDS_LIB standard
J 0
(-2925 4750);
DISPLAY INVISIBLE (-2925 4750);
FORCEPROP 2 LAST ROOM RISER1
J 0
(-3425 4800);
DISPLAY 0.829787 (-3425 4800);
PAINT RED (-3425 4800);
DISPLAY INVISIBLE (-3425 4800);
FORCEPROP 1 LAST BODY_TYPE PLUMBING
J 2
(-2925 4700);
DISPLAY 0.702128 (-2925 4700);
PAINT GREEN (-2925 4700);
DISPLAY INVISIBLE (-2925 4700);
FORCEPROP 1 LAST HDL_TAP TRUE
J 2
(-3250 4625);
DISPLAY 0.702128 (-3250 4625);
PAINT GREEN (-3250 4625);
DISPLAY INVISIBLE (-3250 4625);
FORCEPROP 1 LAST PATH I425
J 2
(-2923 4750);
DISPLAY 0.872340 (-2923 4750);
PAINT GREEN (-2923 4750);
DISPLAY INVISIBLE (-2923 4750);
FORCEADD TAP..6
R 2
(-2925 5050);
FORCEPROP 3 LASTPIN (-2975 5050) SIG_NAME GMI_CPU1_G2_CPU0_G0_TX_DN<8>
J 0
(-2965 5060);
DISPLAY 0.659574 (-2965 5060);
PAINT MONO (-2965 5060);
DISPLAY INVISIBLE (-2965 5060);
FORCEPROP 1 LASTPIN (-2975 5050) BN 8
J 2
(-2923 5058);
DISPLAY 0.489362 (-2923 5058);
PAINT MONO (-2923 5058);
FORCEPROP 2 LAST BOM_COST IO_SLOT
J 0
(-3425 5150);
DISPLAY 0.829787 (-3425 5150);
DISPLAY INVISIBLE (-3425 5150);
FORCEPROP 2 LAST CDS_LIB standard
J 0
(-2925 5050);
DISPLAY INVISIBLE (-2925 5050);
FORCEPROP 2 LAST ROOM RISER1
J 0
(-3425 5100);
DISPLAY 0.829787 (-3425 5100);
PAINT RED (-3425 5100);
DISPLAY INVISIBLE (-3425 5100);
FORCEPROP 1 LAST BODY_TYPE PLUMBING
J 2
(-2925 5000);
DISPLAY 0.702128 (-2925 5000);
PAINT GREEN (-2925 5000);
DISPLAY INVISIBLE (-2925 5000);
FORCEPROP 1 LAST HDL_TAP TRUE
J 2
(-3250 4925);
DISPLAY 0.702128 (-3250 4925);
PAINT GREEN (-3250 4925);
DISPLAY INVISIBLE (-3250 4925);
FORCEPROP 1 LAST PATH I426
J 2
(-2923 5050);
DISPLAY 0.872340 (-2923 5050);
PAINT GREEN (-2923 5050);
DISPLAY INVISIBLE (-2923 5050);
FORCEADD TAP..6
R 2
(-2925 4950);
FORCEPROP 3 LASTPIN (-2975 4950) SIG_NAME GMI_CPU1_G2_CPU0_G0_TX_DN<7>
J 0
(-2965 4960);
DISPLAY 0.659574 (-2965 4960);
PAINT MONO (-2965 4960);
DISPLAY INVISIBLE (-2965 4960);
FORCEPROP 1 LASTPIN (-2975 4950) BN 7
J 2
(-2923 4958);
DISPLAY 0.489362 (-2923 4958);
PAINT MONO (-2923 4958);
FORCEPROP 2 LAST BOM_COST IO_SLOT
J 0
(-3425 5050);
DISPLAY 0.829787 (-3425 5050);
DISPLAY INVISIBLE (-3425 5050);
FORCEPROP 2 LAST CDS_LIB standard
J 0
(-2925 4950);
DISPLAY INVISIBLE (-2925 4950);
FORCEPROP 2 LAST ROOM RISER1
J 0
(-3425 5000);
DISPLAY 0.829787 (-3425 5000);
PAINT RED (-3425 5000);
DISPLAY INVISIBLE (-3425 5000);
FORCEPROP 1 LAST BODY_TYPE PLUMBING
J 2
(-2925 4900);
DISPLAY 0.702128 (-2925 4900);
PAINT GREEN (-2925 4900);
DISPLAY INVISIBLE (-2925 4900);
FORCEPROP 1 LAST HDL_TAP TRUE
J 2
(-3250 4825);
DISPLAY 0.702128 (-3250 4825);
PAINT GREEN (-3250 4825);
DISPLAY INVISIBLE (-3250 4825);
FORCEPROP 1 LAST PATH I427
J 2
(-2923 4950);
DISPLAY 0.872340 (-2923 4950);
PAINT GREEN (-2923 4950);
DISPLAY INVISIBLE (-2923 4950);
FORCEADD TAP..6
R 2
(-2925 4250);
FORCEPROP 3 LASTPIN (-2975 4250) SIG_NAME GMI_CPU1_G2_CPU0_G0_TX_DN<0>
J 0
(-2965 4260);
DISPLAY 0.659574 (-2965 4260);
PAINT MONO (-2965 4260);
DISPLAY INVISIBLE (-2965 4260);
FORCEPROP 1 LASTPIN (-2975 4250) BN 0
J 2
(-2923 4258);
DISPLAY 0.489362 (-2923 4258);
PAINT MONO (-2923 4258);
FORCEPROP 2 LAST BOM_COST IO_SLOT
J 0
(-3425 4350);
DISPLAY 0.829787 (-3425 4350);
DISPLAY INVISIBLE (-3425 4350);
FORCEPROP 2 LAST CDS_LIB standard
J 0
(-2925 4250);
DISPLAY INVISIBLE (-2925 4250);
FORCEPROP 2 LAST ROOM RISER1
J 0
(-3425 4300);
DISPLAY 0.829787 (-3425 4300);
PAINT RED (-3425 4300);
DISPLAY INVISIBLE (-3425 4300);
FORCEPROP 1 LAST BODY_TYPE PLUMBING
J 2
(-2925 4200);
DISPLAY 0.702128 (-2925 4200);
PAINT GREEN (-2925 4200);
DISPLAY INVISIBLE (-2925 4200);
FORCEPROP 1 LAST HDL_TAP TRUE
J 2
(-3250 4125);
DISPLAY 0.702128 (-3250 4125);
PAINT GREEN (-3250 4125);
DISPLAY INVISIBLE (-3250 4125);
FORCEPROP 1 LAST PATH I428
J 2
(-2923 4250);
DISPLAY 0.872340 (-2923 4250);
PAINT GREEN (-2923 4250);
DISPLAY INVISIBLE (-2923 4250);
FORCEADD TAP..6
R 2
(-2925 4550);
FORCEPROP 3 LASTPIN (-2975 4550) SIG_NAME GMI_CPU1_G2_CPU0_G0_TX_DN<3>
J 0
(-2965 4560);
DISPLAY 0.659574 (-2965 4560);
PAINT MONO (-2965 4560);
DISPLAY INVISIBLE (-2965 4560);
FORCEPROP 1 LASTPIN (-2975 4550) BN 3
J 2
(-2923 4558);
DISPLAY 0.489362 (-2923 4558);
PAINT MONO (-2923 4558);
FORCEPROP 2 LAST BOM_COST IO_SLOT
J 0
(-3425 4650);
DISPLAY 0.829787 (-3425 4650);
DISPLAY INVISIBLE (-3425 4650);
FORCEPROP 2 LAST CDS_LIB standard
J 0
(-2925 4550);
DISPLAY INVISIBLE (-2925 4550);
FORCEPROP 2 LAST ROOM RISER1
J 0
(-3425 4600);
DISPLAY 0.829787 (-3425 4600);
PAINT RED (-3425 4600);
DISPLAY INVISIBLE (-3425 4600);
FORCEPROP 1 LAST BODY_TYPE PLUMBING
J 2
(-2925 4500);
DISPLAY 0.702128 (-2925 4500);
PAINT GREEN (-2925 4500);
DISPLAY INVISIBLE (-2925 4500);
FORCEPROP 1 LAST HDL_TAP TRUE
J 2
(-3250 4425);
DISPLAY 0.702128 (-3250 4425);
PAINT GREEN (-3250 4425);
DISPLAY INVISIBLE (-3250 4425);
FORCEPROP 1 LAST PATH I429
J 2
(-2923 4550);
DISPLAY 0.872340 (-2923 4550);
PAINT GREEN (-2923 4550);
DISPLAY INVISIBLE (-2923 4550);
FORCEADD TAP..6
R 2
(-2925 4450);
FORCEPROP 3 LASTPIN (-2975 4450) SIG_NAME GMI_CPU1_G2_CPU0_G0_TX_DN<2>
J 0
(-2965 4460);
DISPLAY 0.659574 (-2965 4460);
PAINT MONO (-2965 4460);
DISPLAY INVISIBLE (-2965 4460);
FORCEPROP 1 LASTPIN (-2975 4450) BN 2
J 2
(-2923 4458);
DISPLAY 0.489362 (-2923 4458);
PAINT MONO (-2923 4458);
FORCEPROP 2 LAST BOM_COST IO_SLOT
J 0
(-3425 4550);
DISPLAY 0.829787 (-3425 4550);
DISPLAY INVISIBLE (-3425 4550);
FORCEPROP 2 LAST CDS_LIB standard
J 0
(-2925 4450);
DISPLAY INVISIBLE (-2925 4450);
FORCEPROP 2 LAST ROOM RISER1
J 0
(-3425 4500);
DISPLAY 0.829787 (-3425 4500);
PAINT RED (-3425 4500);
DISPLAY INVISIBLE (-3425 4500);
FORCEPROP 1 LAST BODY_TYPE PLUMBING
J 2
(-2925 4400);
DISPLAY 0.702128 (-2925 4400);
PAINT GREEN (-2925 4400);
DISPLAY INVISIBLE (-2925 4400);
FORCEPROP 1 LAST HDL_TAP TRUE
J 2
(-3250 4325);
DISPLAY 0.702128 (-3250 4325);
PAINT GREEN (-3250 4325);
DISPLAY INVISIBLE (-3250 4325);
FORCEPROP 1 LAST PATH I430
J 2
(-2923 4450);
DISPLAY 0.872340 (-2923 4450);
PAINT GREEN (-2923 4450);
DISPLAY INVISIBLE (-2923 4450);
FORCEADD TAP..6
R 2
(-2925 4350);
FORCEPROP 3 LASTPIN (-2975 4350) SIG_NAME GMI_CPU1_G2_CPU0_G0_TX_DN<1>
J 0
(-2965 4360);
DISPLAY 0.659574 (-2965 4360);
PAINT MONO (-2965 4360);
DISPLAY INVISIBLE (-2965 4360);
FORCEPROP 1 LASTPIN (-2975 4350) BN 1
J 2
(-2923 4358);
DISPLAY 0.489362 (-2923 4358);
PAINT MONO (-2923 4358);
FORCEPROP 2 LAST CDS_LIB standard
J 0
(-2925 4350);
DISPLAY INVISIBLE (-2925 4350);
FORCEPROP 2 LAST BOM_COST IO_SLOT
J 0
(-3425 4450);
DISPLAY 0.829787 (-3425 4450);
DISPLAY INVISIBLE (-3425 4450);
FORCEPROP 2 LAST ROOM RISER1
J 0
(-3425 4400);
DISPLAY 0.829787 (-3425 4400);
PAINT RED (-3425 4400);
DISPLAY INVISIBLE (-3425 4400);
FORCEPROP 1 LAST BODY_TYPE PLUMBING
J 2
(-2925 4300);
DISPLAY 0.702128 (-2925 4300);
PAINT GREEN (-2925 4300);
DISPLAY INVISIBLE (-2925 4300);
FORCEPROP 1 LAST HDL_TAP TRUE
J 2
(-3250 4225);
DISPLAY 0.702128 (-3250 4225);
PAINT GREEN (-3250 4225);
DISPLAY INVISIBLE (-3250 4225);
FORCEPROP 1 LAST PATH I431
J 2
(-2923 4350);
DISPLAY 0.872340 (-2923 4350);
PAINT GREEN (-2923 4350);
DISPLAY INVISIBLE (-2923 4350);
FORCEADD OFFPAGE..2
(-1775 3300);
FORCEPROP 2 LAST $XR0 22 
J 0
(-1586 3300);
DISPLAY 0.638298 (-1586 3300);
PAINT MONO (-1586 3300);
FORCEPROP 2 LAST CDS_LIB standard
J 0
(-1775 3300);
DISPLAY INVISIBLE (-1775 3300);
FORCEPROP 1 LAST OFFPAGE TRUE
J 0
(-1450 3175);
DISPLAY 0.872340 (-1450 3175);
PAINT GREEN (-1450 3175);
DISPLAY INVISIBLE (-1450 3175);
FORCEPROP 1 LAST COMMENT_BODY TRUE
J 0
(-1820 3205);
DISPLAY 0.872340 (-1820 3205);
PAINT GREEN (-1820 3205);
DISPLAY INVISIBLE (-1820 3205);
FORCEPROP 2 LAST PATH I432
J 0
(-1575 3350);
DISPLAY 1.021277 (-1575 3350);
DISPLAY INVISIBLE (-1575 3350);
FORCEADD TAP..6
R 2
(-2900 3075);
FORCEPROP 3 LASTPIN (-2950 3075) SIG_NAME GMI_CPU1_G3_CPU0_G1_TX_DN<15>
J 0
(-2940 3085);
DISPLAY 0.659574 (-2940 3085);
PAINT MONO (-2940 3085);
DISPLAY INVISIBLE (-2940 3085);
FORCEPROP 1 LASTPIN (-2950 3075) BN 15
J 2
(-2898 3083);
DISPLAY 0.489362 (-2898 3083);
PAINT MONO (-2898 3083);
FORCEPROP 2 LAST BOM_COST IO_SLOT
J 0
(-3400 3175);
DISPLAY 0.829787 (-3400 3175);
DISPLAY INVISIBLE (-3400 3175);
FORCEPROP 2 LAST CDS_LIB mstr_standard
J 0
(-2900 3075);
DISPLAY INVISIBLE (-2900 3075);
FORCEPROP 2 LAST ROOM RISER1
J 0
(-3400 3125);
DISPLAY 0.829787 (-3400 3125);
PAINT RED (-3400 3125);
DISPLAY INVISIBLE (-3400 3125);
FORCEPROP 1 LAST BODY_TYPE PLUMBING
J 2
(-2900 3025);
DISPLAY 0.702128 (-2900 3025);
PAINT GREEN (-2900 3025);
DISPLAY INVISIBLE (-2900 3025);
FORCEPROP 1 LAST HDL_TAP TRUE
J 2
(-3225 2950);
DISPLAY 0.702128 (-3225 2950);
PAINT GREEN (-3225 2950);
DISPLAY INVISIBLE (-3225 2950);
FORCEPROP 1 LAST PATH I433
J 2
(-2898 3075);
DISPLAY 0.872340 (-2898 3075);
PAINT GREEN (-2898 3075);
DISPLAY INVISIBLE (-2898 3075);
FORCEADD TAP..6
R 2
(-2900 2975);
FORCEPROP 3 LASTPIN (-2950 2975) SIG_NAME GMI_CPU1_G3_CPU0_G1_TX_DN<14>
J 0
(-2940 2985);
DISPLAY 0.659574 (-2940 2985);
PAINT MONO (-2940 2985);
DISPLAY INVISIBLE (-2940 2985);
FORCEPROP 1 LASTPIN (-2950 2975) BN 14
J 2
(-2898 2983);
DISPLAY 0.489362 (-2898 2983);
PAINT MONO (-2898 2983);
FORCEPROP 2 LAST CDS_LIB mstr_standard
J 0
(-2900 2975);
DISPLAY INVISIBLE (-2900 2975);
FORCEPROP 2 LAST BOM_COST IO_SLOT
J 0
(-3400 3075);
DISPLAY 0.829787 (-3400 3075);
DISPLAY INVISIBLE (-3400 3075);
FORCEPROP 2 LAST ROOM RISER1
J 0
(-3400 3025);
DISPLAY 0.829787 (-3400 3025);
PAINT RED (-3400 3025);
DISPLAY INVISIBLE (-3400 3025);
FORCEPROP 1 LAST BODY_TYPE PLUMBING
J 2
(-2900 2925);
DISPLAY 0.702128 (-2900 2925);
PAINT GREEN (-2900 2925);
DISPLAY INVISIBLE (-2900 2925);
FORCEPROP 1 LAST HDL_TAP TRUE
J 2
(-3225 2850);
DISPLAY 0.702128 (-3225 2850);
PAINT GREEN (-3225 2850);
DISPLAY INVISIBLE (-3225 2850);
FORCEPROP 1 LAST PATH I434
J 2
(-2898 2975);
DISPLAY 0.872340 (-2898 2975);
PAINT GREEN (-2898 2975);
DISPLAY INVISIBLE (-2898 2975);
FORCEADD TAP..6
R 2
(-2900 2875);
FORCEPROP 3 LASTPIN (-2950 2875) SIG_NAME GMI_CPU1_G3_CPU0_G1_TX_DN<13>
J 0
(-2940 2885);
DISPLAY 0.659574 (-2940 2885);
PAINT MONO (-2940 2885);
DISPLAY INVISIBLE (-2940 2885);
FORCEPROP 1 LASTPIN (-2950 2875) BN 13
J 2
(-2898 2883);
DISPLAY 0.489362 (-2898 2883);
PAINT MONO (-2898 2883);
FORCEPROP 2 LAST CDS_LIB standard
J 0
(-2900 2875);
DISPLAY INVISIBLE (-2900 2875);
FORCEPROP 2 LAST BOM_COST IO_SLOT
J 0
(-3400 2975);
DISPLAY 0.829787 (-3400 2975);
DISPLAY INVISIBLE (-3400 2975);
FORCEPROP 2 LAST ROOM RISER1
J 0
(-3400 2925);
DISPLAY 0.829787 (-3400 2925);
PAINT RED (-3400 2925);
DISPLAY INVISIBLE (-3400 2925);
FORCEPROP 1 LAST BODY_TYPE PLUMBING
J 2
(-2900 2825);
DISPLAY 0.702128 (-2900 2825);
PAINT GREEN (-2900 2825);
DISPLAY INVISIBLE (-2900 2825);
FORCEPROP 1 LAST HDL_TAP TRUE
J 2
(-3225 2750);
DISPLAY 0.702128 (-3225 2750);
PAINT GREEN (-3225 2750);
DISPLAY INVISIBLE (-3225 2750);
FORCEPROP 1 LAST PATH I435
J 2
(-2898 2875);
DISPLAY 0.872340 (-2898 2875);
PAINT GREEN (-2898 2875);
DISPLAY INVISIBLE (-2898 2875);
FORCEADD TAP..6
R 2
(-2900 2775);
FORCEPROP 3 LASTPIN (-2950 2775) SIG_NAME GMI_CPU1_G3_CPU0_G1_TX_DN<12>
J 0
(-2940 2785);
DISPLAY 0.659574 (-2940 2785);
PAINT MONO (-2940 2785);
DISPLAY INVISIBLE (-2940 2785);
FORCEPROP 1 LASTPIN (-2950 2775) BN 12
J 2
(-2898 2783);
DISPLAY 0.489362 (-2898 2783);
PAINT MONO (-2898 2783);
FORCEPROP 2 LAST CDS_LIB standard
J 0
(-2900 2775);
DISPLAY INVISIBLE (-2900 2775);
FORCEPROP 2 LAST BOM_COST IO_SLOT
J 0
(-3400 2875);
DISPLAY 0.829787 (-3400 2875);
DISPLAY INVISIBLE (-3400 2875);
FORCEPROP 2 LAST ROOM RISER1
J 0
(-3400 2825);
DISPLAY 0.829787 (-3400 2825);
PAINT RED (-3400 2825);
DISPLAY INVISIBLE (-3400 2825);
FORCEPROP 1 LAST BODY_TYPE PLUMBING
J 2
(-2900 2725);
DISPLAY 0.702128 (-2900 2725);
PAINT GREEN (-2900 2725);
DISPLAY INVISIBLE (-2900 2725);
FORCEPROP 1 LAST HDL_TAP TRUE
J 2
(-3225 2650);
DISPLAY 0.702128 (-3225 2650);
PAINT GREEN (-3225 2650);
DISPLAY INVISIBLE (-3225 2650);
FORCEPROP 1 LAST PATH I436
J 2
(-2898 2775);
DISPLAY 0.872340 (-2898 2775);
PAINT GREEN (-2898 2775);
DISPLAY INVISIBLE (-2898 2775);
FORCEADD TAP..6
R 2
(-2900 2675);
FORCEPROP 3 LASTPIN (-2950 2675) SIG_NAME GMI_CPU1_G3_CPU0_G1_TX_DN<11>
J 0
(-2940 2685);
DISPLAY 0.659574 (-2940 2685);
PAINT MONO (-2940 2685);
DISPLAY INVISIBLE (-2940 2685);
FORCEPROP 1 LASTPIN (-2950 2675) BN 11
J 2
(-2898 2683);
DISPLAY 0.489362 (-2898 2683);
PAINT MONO (-2898 2683);
FORCEPROP 2 LAST CDS_LIB standard
J 0
(-2900 2675);
DISPLAY INVISIBLE (-2900 2675);
FORCEPROP 2 LAST BOM_COST IO_SLOT
J 0
(-3400 2775);
DISPLAY 0.829787 (-3400 2775);
DISPLAY INVISIBLE (-3400 2775);
FORCEPROP 2 LAST ROOM RISER1
J 0
(-3400 2725);
DISPLAY 0.829787 (-3400 2725);
PAINT RED (-3400 2725);
DISPLAY INVISIBLE (-3400 2725);
FORCEPROP 1 LAST BODY_TYPE PLUMBING
J 2
(-2900 2625);
DISPLAY 0.702128 (-2900 2625);
PAINT GREEN (-2900 2625);
DISPLAY INVISIBLE (-2900 2625);
FORCEPROP 1 LAST HDL_TAP TRUE
J 2
(-3225 2550);
DISPLAY 0.702128 (-3225 2550);
PAINT GREEN (-3225 2550);
DISPLAY INVISIBLE (-3225 2550);
FORCEPROP 1 LAST PATH I437
J 2
(-2898 2675);
DISPLAY 0.872340 (-2898 2675);
PAINT GREEN (-2898 2675);
DISPLAY INVISIBLE (-2898 2675);
FORCEADD TAP..6
R 2
(-2900 2575);
FORCEPROP 3 LASTPIN (-2950 2575) SIG_NAME GMI_CPU1_G3_CPU0_G1_TX_DN<10>
J 0
(-2940 2585);
DISPLAY 0.659574 (-2940 2585);
PAINT MONO (-2940 2585);
DISPLAY INVISIBLE (-2940 2585);
FORCEPROP 1 LASTPIN (-2950 2575) BN 10
J 2
(-2898 2583);
DISPLAY 0.489362 (-2898 2583);
PAINT MONO (-2898 2583);
FORCEPROP 2 LAST CDS_LIB standard
J 0
(-2900 2575);
DISPLAY INVISIBLE (-2900 2575);
FORCEPROP 2 LAST BOM_COST IO_SLOT
J 0
(-3400 2675);
DISPLAY 0.829787 (-3400 2675);
DISPLAY INVISIBLE (-3400 2675);
FORCEPROP 2 LAST ROOM RISER1
J 0
(-3400 2625);
DISPLAY 0.829787 (-3400 2625);
PAINT RED (-3400 2625);
DISPLAY INVISIBLE (-3400 2625);
FORCEPROP 1 LAST BODY_TYPE PLUMBING
J 2
(-2900 2525);
DISPLAY 0.702128 (-2900 2525);
PAINT GREEN (-2900 2525);
DISPLAY INVISIBLE (-2900 2525);
FORCEPROP 1 LAST HDL_TAP TRUE
J 2
(-3225 2450);
DISPLAY 0.702128 (-3225 2450);
PAINT GREEN (-3225 2450);
DISPLAY INVISIBLE (-3225 2450);
FORCEPROP 1 LAST PATH I438
J 2
(-2898 2575);
DISPLAY 0.872340 (-2898 2575);
PAINT GREEN (-2898 2575);
DISPLAY INVISIBLE (-2898 2575);
FORCEADD TAP..6
R 2
(-2900 2475);
FORCEPROP 3 LASTPIN (-2950 2475) SIG_NAME GMI_CPU1_G3_CPU0_G1_TX_DN<9>
J 0
(-2940 2485);
DISPLAY 0.659574 (-2940 2485);
PAINT MONO (-2940 2485);
DISPLAY INVISIBLE (-2940 2485);
FORCEPROP 1 LASTPIN (-2950 2475) BN 9
J 2
(-2898 2483);
DISPLAY 0.489362 (-2898 2483);
PAINT MONO (-2898 2483);
FORCEPROP 2 LAST CDS_LIB standard
J 0
(-2900 2475);
DISPLAY INVISIBLE (-2900 2475);
FORCEPROP 2 LAST BOM_COST IO_SLOT
J 0
(-3400 2575);
DISPLAY 0.829787 (-3400 2575);
DISPLAY INVISIBLE (-3400 2575);
FORCEPROP 2 LAST ROOM RISER1
J 0
(-3400 2525);
DISPLAY 0.829787 (-3400 2525);
PAINT RED (-3400 2525);
DISPLAY INVISIBLE (-3400 2525);
FORCEPROP 1 LAST BODY_TYPE PLUMBING
J 2
(-2900 2425);
DISPLAY 0.702128 (-2900 2425);
PAINT GREEN (-2900 2425);
DISPLAY INVISIBLE (-2900 2425);
FORCEPROP 1 LAST HDL_TAP TRUE
J 2
(-3225 2350);
DISPLAY 0.702128 (-3225 2350);
PAINT GREEN (-3225 2350);
DISPLAY INVISIBLE (-3225 2350);
FORCEPROP 1 LAST PATH I439
J 2
(-2898 2475);
DISPLAY 0.872340 (-2898 2475);
PAINT GREEN (-2898 2475);
DISPLAY INVISIBLE (-2898 2475);
FORCEADD TAP..6
R 2
(-2900 2375);
FORCEPROP 3 LASTPIN (-2950 2375) SIG_NAME GMI_CPU1_G3_CPU0_G1_TX_DN<8>
J 0
(-2940 2385);
DISPLAY 0.659574 (-2940 2385);
PAINT MONO (-2940 2385);
DISPLAY INVISIBLE (-2940 2385);
FORCEPROP 1 LASTPIN (-2950 2375) BN 8
J 2
(-2898 2383);
DISPLAY 0.489362 (-2898 2383);
PAINT MONO (-2898 2383);
FORCEPROP 2 LAST CDS_LIB standard
J 0
(-2900 2375);
DISPLAY INVISIBLE (-2900 2375);
FORCEPROP 2 LAST BOM_COST IO_SLOT
J 0
(-3400 2475);
DISPLAY 0.829787 (-3400 2475);
DISPLAY INVISIBLE (-3400 2475);
FORCEPROP 2 LAST ROOM RISER1
J 0
(-3400 2425);
DISPLAY 0.829787 (-3400 2425);
PAINT RED (-3400 2425);
DISPLAY INVISIBLE (-3400 2425);
FORCEPROP 1 LAST BODY_TYPE PLUMBING
J 2
(-2900 2325);
DISPLAY 0.702128 (-2900 2325);
PAINT GREEN (-2900 2325);
DISPLAY INVISIBLE (-2900 2325);
FORCEPROP 1 LAST HDL_TAP TRUE
J 2
(-3225 2250);
DISPLAY 0.702128 (-3225 2250);
PAINT GREEN (-3225 2250);
DISPLAY INVISIBLE (-3225 2250);
FORCEPROP 1 LAST PATH I440
J 2
(-2898 2375);
DISPLAY 0.872340 (-2898 2375);
PAINT GREEN (-2898 2375);
DISPLAY INVISIBLE (-2898 2375);
FORCEADD TAP..6
R 2
(-2900 2275);
FORCEPROP 3 LASTPIN (-2950 2275) SIG_NAME GMI_CPU1_G3_CPU0_G1_TX_DN<7>
J 0
(-2940 2285);
DISPLAY 0.659574 (-2940 2285);
PAINT MONO (-2940 2285);
DISPLAY INVISIBLE (-2940 2285);
FORCEPROP 1 LASTPIN (-2950 2275) BN 7
J 2
(-2898 2283);
DISPLAY 0.489362 (-2898 2283);
PAINT MONO (-2898 2283);
FORCEPROP 2 LAST CDS_LIB standard
J 0
(-2900 2275);
DISPLAY INVISIBLE (-2900 2275);
FORCEPROP 2 LAST BOM_COST IO_SLOT
J 0
(-3400 2375);
DISPLAY 0.829787 (-3400 2375);
DISPLAY INVISIBLE (-3400 2375);
FORCEPROP 2 LAST ROOM RISER1
J 0
(-3400 2325);
DISPLAY 0.829787 (-3400 2325);
PAINT RED (-3400 2325);
DISPLAY INVISIBLE (-3400 2325);
FORCEPROP 1 LAST BODY_TYPE PLUMBING
J 2
(-2900 2225);
DISPLAY 0.702128 (-2900 2225);
PAINT GREEN (-2900 2225);
DISPLAY INVISIBLE (-2900 2225);
FORCEPROP 1 LAST HDL_TAP TRUE
J 2
(-3225 2150);
DISPLAY 0.702128 (-3225 2150);
PAINT GREEN (-3225 2150);
DISPLAY INVISIBLE (-3225 2150);
FORCEPROP 1 LAST PATH I441
J 2
(-2898 2275);
DISPLAY 0.872340 (-2898 2275);
PAINT GREEN (-2898 2275);
DISPLAY INVISIBLE (-2898 2275);
FORCEADD TAP..6
R 2
(-2900 2175);
FORCEPROP 3 LASTPIN (-2950 2175) SIG_NAME GMI_CPU1_G3_CPU0_G1_TX_DN<6>
J 0
(-2940 2185);
DISPLAY 0.659574 (-2940 2185);
PAINT MONO (-2940 2185);
DISPLAY INVISIBLE (-2940 2185);
FORCEPROP 1 LASTPIN (-2950 2175) BN 6
J 2
(-2898 2183);
DISPLAY 0.489362 (-2898 2183);
PAINT MONO (-2898 2183);
FORCEPROP 2 LAST CDS_LIB standard
J 0
(-2900 2175);
DISPLAY INVISIBLE (-2900 2175);
FORCEPROP 2 LAST BOM_COST IO_SLOT
J 0
(-3400 2275);
DISPLAY 0.829787 (-3400 2275);
DISPLAY INVISIBLE (-3400 2275);
FORCEPROP 2 LAST ROOM RISER1
J 0
(-3400 2225);
DISPLAY 0.829787 (-3400 2225);
PAINT RED (-3400 2225);
DISPLAY INVISIBLE (-3400 2225);
FORCEPROP 1 LAST BODY_TYPE PLUMBING
J 2
(-2900 2125);
DISPLAY 0.702128 (-2900 2125);
PAINT GREEN (-2900 2125);
DISPLAY INVISIBLE (-2900 2125);
FORCEPROP 1 LAST HDL_TAP TRUE
J 2
(-3225 2050);
DISPLAY 0.702128 (-3225 2050);
PAINT GREEN (-3225 2050);
DISPLAY INVISIBLE (-3225 2050);
FORCEPROP 1 LAST PATH I442
J 2
(-2898 2175);
DISPLAY 0.872340 (-2898 2175);
PAINT GREEN (-2898 2175);
DISPLAY INVISIBLE (-2898 2175);
FORCEADD TAP..6
R 2
(-2900 2075);
FORCEPROP 3 LASTPIN (-2950 2075) SIG_NAME GMI_CPU1_G3_CPU0_G1_TX_DN<5>
J 0
(-2940 2085);
DISPLAY 0.659574 (-2940 2085);
PAINT MONO (-2940 2085);
DISPLAY INVISIBLE (-2940 2085);
FORCEPROP 1 LASTPIN (-2950 2075) BN 5
J 2
(-2898 2083);
DISPLAY 0.489362 (-2898 2083);
PAINT MONO (-2898 2083);
FORCEPROP 2 LAST CDS_LIB standard
J 0
(-2900 2075);
DISPLAY INVISIBLE (-2900 2075);
FORCEPROP 2 LAST BOM_COST IO_SLOT
J 0
(-3400 2175);
DISPLAY 0.829787 (-3400 2175);
DISPLAY INVISIBLE (-3400 2175);
FORCEPROP 2 LAST ROOM RISER1
J 0
(-3400 2125);
DISPLAY 0.829787 (-3400 2125);
PAINT RED (-3400 2125);
DISPLAY INVISIBLE (-3400 2125);
FORCEPROP 1 LAST BODY_TYPE PLUMBING
J 2
(-2900 2025);
DISPLAY 0.702128 (-2900 2025);
PAINT GREEN (-2900 2025);
DISPLAY INVISIBLE (-2900 2025);
FORCEPROP 1 LAST HDL_TAP TRUE
J 2
(-3225 1950);
DISPLAY 0.702128 (-3225 1950);
PAINT GREEN (-3225 1950);
DISPLAY INVISIBLE (-3225 1950);
FORCEPROP 1 LAST PATH I443
J 2
(-2898 2075);
DISPLAY 0.872340 (-2898 2075);
PAINT GREEN (-2898 2075);
DISPLAY INVISIBLE (-2898 2075);
FORCEADD TAP..6
R 2
(-2900 1975);
FORCEPROP 3 LASTPIN (-2950 1975) SIG_NAME GMI_CPU1_G3_CPU0_G1_TX_DN<4>
J 0
(-2940 1985);
DISPLAY 0.659574 (-2940 1985);
PAINT MONO (-2940 1985);
DISPLAY INVISIBLE (-2940 1985);
FORCEPROP 1 LASTPIN (-2950 1975) BN 4
J 2
(-2898 1983);
DISPLAY 0.489362 (-2898 1983);
PAINT MONO (-2898 1983);
FORCEPROP 2 LAST CDS_LIB standard
J 0
(-2900 1975);
DISPLAY INVISIBLE (-2900 1975);
FORCEPROP 2 LAST BOM_COST IO_SLOT
J 0
(-3400 2075);
DISPLAY 0.829787 (-3400 2075);
DISPLAY INVISIBLE (-3400 2075);
FORCEPROP 2 LAST ROOM RISER1
J 0
(-3400 2025);
DISPLAY 0.829787 (-3400 2025);
PAINT RED (-3400 2025);
DISPLAY INVISIBLE (-3400 2025);
FORCEPROP 1 LAST BODY_TYPE PLUMBING
J 2
(-2900 1925);
DISPLAY 0.702128 (-2900 1925);
PAINT GREEN (-2900 1925);
DISPLAY INVISIBLE (-2900 1925);
FORCEPROP 1 LAST HDL_TAP TRUE
J 2
(-3225 1850);
DISPLAY 0.702128 (-3225 1850);
PAINT GREEN (-3225 1850);
DISPLAY INVISIBLE (-3225 1850);
FORCEPROP 1 LAST PATH I444
J 2
(-2898 1975);
DISPLAY 0.872340 (-2898 1975);
PAINT GREEN (-2898 1975);
DISPLAY INVISIBLE (-2898 1975);
FORCEADD TAP..6
R 2
(-2900 1875);
FORCEPROP 3 LASTPIN (-2950 1875) SIG_NAME GMI_CPU1_G3_CPU0_G1_TX_DN<3>
J 0
(-2940 1885);
DISPLAY 0.659574 (-2940 1885);
PAINT MONO (-2940 1885);
DISPLAY INVISIBLE (-2940 1885);
FORCEPROP 1 LASTPIN (-2950 1875) BN 3
J 2
(-2898 1883);
DISPLAY 0.489362 (-2898 1883);
PAINT MONO (-2898 1883);
FORCEPROP 2 LAST CDS_LIB standard
J 0
(-2900 1875);
DISPLAY INVISIBLE (-2900 1875);
FORCEPROP 2 LAST BOM_COST IO_SLOT
J 0
(-3400 1975);
DISPLAY 0.829787 (-3400 1975);
DISPLAY INVISIBLE (-3400 1975);
FORCEPROP 2 LAST ROOM RISER1
J 0
(-3400 1925);
DISPLAY 0.829787 (-3400 1925);
PAINT RED (-3400 1925);
DISPLAY INVISIBLE (-3400 1925);
FORCEPROP 1 LAST BODY_TYPE PLUMBING
J 2
(-2900 1825);
DISPLAY 0.702128 (-2900 1825);
PAINT GREEN (-2900 1825);
DISPLAY INVISIBLE (-2900 1825);
FORCEPROP 1 LAST HDL_TAP TRUE
J 2
(-3225 1750);
DISPLAY 0.702128 (-3225 1750);
PAINT GREEN (-3225 1750);
DISPLAY INVISIBLE (-3225 1750);
FORCEPROP 1 LAST PATH I445
J 2
(-2898 1875);
DISPLAY 0.872340 (-2898 1875);
PAINT GREEN (-2898 1875);
DISPLAY INVISIBLE (-2898 1875);
FORCEADD TAP..6
R 2
(-2900 1675);
FORCEPROP 3 LASTPIN (-2950 1675) SIG_NAME GMI_CPU1_G3_CPU0_G1_TX_DN<1>
J 0
(-2940 1685);
DISPLAY 0.659574 (-2940 1685);
PAINT MONO (-2940 1685);
DISPLAY INVISIBLE (-2940 1685);
FORCEPROP 1 LASTPIN (-2950 1675) BN 1
J 2
(-2898 1683);
DISPLAY 0.489362 (-2898 1683);
PAINT MONO (-2898 1683);
FORCEPROP 2 LAST BOM_COST IO_SLOT
J 0
(-3400 1775);
DISPLAY 0.829787 (-3400 1775);
DISPLAY INVISIBLE (-3400 1775);
FORCEPROP 2 LAST CDS_LIB standard
J 0
(-2900 1675);
DISPLAY INVISIBLE (-2900 1675);
FORCEPROP 2 LAST ROOM RISER1
J 0
(-3400 1725);
DISPLAY 0.829787 (-3400 1725);
PAINT RED (-3400 1725);
DISPLAY INVISIBLE (-3400 1725);
FORCEPROP 1 LAST BODY_TYPE PLUMBING
J 2
(-2900 1625);
DISPLAY 0.702128 (-2900 1625);
PAINT GREEN (-2900 1625);
DISPLAY INVISIBLE (-2900 1625);
FORCEPROP 1 LAST HDL_TAP TRUE
J 2
(-3225 1550);
DISPLAY 0.702128 (-3225 1550);
PAINT GREEN (-3225 1550);
DISPLAY INVISIBLE (-3225 1550);
FORCEPROP 1 LAST PATH I446
J 2
(-2898 1675);
DISPLAY 0.872340 (-2898 1675);
PAINT GREEN (-2898 1675);
DISPLAY INVISIBLE (-2898 1675);
FORCEADD TAP..6
R 2
(-2900 1775);
FORCEPROP 3 LASTPIN (-2950 1775) SIG_NAME GMI_CPU1_G3_CPU0_G1_TX_DN<2>
J 0
(-2940 1785);
DISPLAY 0.659574 (-2940 1785);
PAINT MONO (-2940 1785);
DISPLAY INVISIBLE (-2940 1785);
FORCEPROP 1 LASTPIN (-2950 1775) BN 2
J 2
(-2898 1783);
DISPLAY 0.489362 (-2898 1783);
PAINT MONO (-2898 1783);
FORCEPROP 2 LAST CDS_LIB standard
J 0
(-2900 1775);
DISPLAY INVISIBLE (-2900 1775);
FORCEPROP 2 LAST BOM_COST IO_SLOT
J 0
(-3400 1875);
DISPLAY 0.829787 (-3400 1875);
DISPLAY INVISIBLE (-3400 1875);
FORCEPROP 2 LAST ROOM RISER1
J 0
(-3400 1825);
DISPLAY 0.829787 (-3400 1825);
PAINT RED (-3400 1825);
DISPLAY INVISIBLE (-3400 1825);
FORCEPROP 1 LAST BODY_TYPE PLUMBING
J 2
(-2900 1725);
DISPLAY 0.702128 (-2900 1725);
PAINT GREEN (-2900 1725);
DISPLAY INVISIBLE (-2900 1725);
FORCEPROP 1 LAST HDL_TAP TRUE
J 2
(-3225 1650);
DISPLAY 0.702128 (-3225 1650);
PAINT GREEN (-3225 1650);
DISPLAY INVISIBLE (-3225 1650);
FORCEPROP 1 LAST PATH I447
J 2
(-2898 1775);
DISPLAY 0.872340 (-2898 1775);
PAINT GREEN (-2898 1775);
DISPLAY INVISIBLE (-2898 1775);
FORCEADD TAP..6
R 2
(-2900 1575);
FORCEPROP 3 LASTPIN (-2950 1575) SIG_NAME GMI_CPU1_G3_CPU0_G1_TX_DN<0>
J 0
(-2940 1585);
DISPLAY 0.659574 (-2940 1585);
PAINT MONO (-2940 1585);
DISPLAY INVISIBLE (-2940 1585);
FORCEPROP 1 LASTPIN (-2950 1575) BN 0
J 2
(-2898 1583);
DISPLAY 0.489362 (-2898 1583);
PAINT MONO (-2898 1583);
FORCEPROP 2 LAST CDS_LIB standard
J 0
(-2900 1575);
DISPLAY INVISIBLE (-2900 1575);
FORCEPROP 2 LAST BOM_COST IO_SLOT
J 0
(-3400 1675);
DISPLAY 0.829787 (-3400 1675);
DISPLAY INVISIBLE (-3400 1675);
FORCEPROP 2 LAST ROOM RISER1
J 0
(-3400 1625);
DISPLAY 0.829787 (-3400 1625);
PAINT RED (-3400 1625);
DISPLAY INVISIBLE (-3400 1625);
FORCEPROP 1 LAST BODY_TYPE PLUMBING
J 2
(-2900 1525);
DISPLAY 0.702128 (-2900 1525);
PAINT GREEN (-2900 1525);
DISPLAY INVISIBLE (-2900 1525);
FORCEPROP 1 LAST HDL_TAP TRUE
J 2
(-3225 1450);
DISPLAY 0.702128 (-3225 1450);
PAINT GREEN (-3225 1450);
DISPLAY INVISIBLE (-3225 1450);
FORCEPROP 1 LAST PATH I448
J 2
(-2898 1575);
DISPLAY 0.872340 (-2898 1575);
PAINT GREEN (-2898 1575);
DISPLAY INVISIBLE (-2898 1575);
FORCEADD TAP..6
(-6625 3075);
FORCEPROP 3 LASTPIN (-6575 3075) SIG_NAME GMI_CPU0_G1_CPU1_G3_TX_DN<15>
J 0
(-6565 3085);
DISPLAY 0.659574 (-6565 3085);
PAINT MONO (-6565 3085);
DISPLAY INVISIBLE (-6565 3085);
FORCEPROP 1 LASTPIN (-6575 3075) BN 15
J 0
(-6627 3083);
DISPLAY 0.489362 (-6627 3083);
PAINT MONO (-6627 3083);
FORCEPROP 2 LAST CDS_LIB mstr_standard
J 0
(-6625 3075);
DISPLAY INVISIBLE (-6625 3075);
FORCEPROP 1 LAST BODY_TYPE PLUMBING
J 0
(-6625 3025);
DISPLAY 0.574468 (-6625 3025);
PAINT GREEN (-6625 3025);
DISPLAY INVISIBLE (-6625 3025);
FORCEPROP 1 LAST HDL_TAP TRUE
J 0
(-6300 2950);
DISPLAY 0.574468 (-6300 2950);
PAINT GREEN (-6300 2950);
DISPLAY INVISIBLE (-6300 2950);
FORCEPROP 1 LAST PATH I449
J 0
(-6627 3075);
DISPLAY 0.872340 (-6627 3075);
PAINT GREEN (-6627 3075);
DISPLAY INVISIBLE (-6627 3075);
FORCEADD TAP..6
(-6625 2975);
FORCEPROP 3 LASTPIN (-6575 2975) SIG_NAME GMI_CPU0_G1_CPU1_G3_TX_DN<14>
J 0
(-6565 2985);
DISPLAY 0.659574 (-6565 2985);
PAINT MONO (-6565 2985);
DISPLAY INVISIBLE (-6565 2985);
FORCEPROP 1 LASTPIN (-6575 2975) BN 14
J 0
(-6627 2983);
DISPLAY 0.489362 (-6627 2983);
PAINT MONO (-6627 2983);
FORCEPROP 2 LAST CDS_LIB mstr_standard
J 0
(-6625 2975);
DISPLAY INVISIBLE (-6625 2975);
FORCEPROP 1 LAST BODY_TYPE PLUMBING
J 0
(-6625 2925);
DISPLAY 0.574468 (-6625 2925);
PAINT GREEN (-6625 2925);
DISPLAY INVISIBLE (-6625 2925);
FORCEPROP 1 LAST HDL_TAP TRUE
J 0
(-6300 2850);
DISPLAY 0.574468 (-6300 2850);
PAINT GREEN (-6300 2850);
DISPLAY INVISIBLE (-6300 2850);
FORCEPROP 1 LAST PATH I450
J 0
(-6627 2975);
DISPLAY 0.872340 (-6627 2975);
PAINT GREEN (-6627 2975);
DISPLAY INVISIBLE (-6627 2975);
FORCEADD TAP..6
(-6625 2875);
FORCEPROP 3 LASTPIN (-6575 2875) SIG_NAME GMI_CPU0_G1_CPU1_G3_TX_DN<13>
J 0
(-6565 2885);
DISPLAY 0.659574 (-6565 2885);
PAINT MONO (-6565 2885);
DISPLAY INVISIBLE (-6565 2885);
FORCEPROP 1 LASTPIN (-6575 2875) BN 13
J 0
(-6627 2883);
DISPLAY 0.489362 (-6627 2883);
PAINT MONO (-6627 2883);
FORCEPROP 2 LAST CDS_LIB standard
J 0
(-6625 2875);
DISPLAY INVISIBLE (-6625 2875);
FORCEPROP 1 LAST BODY_TYPE PLUMBING
J 0
(-6625 2825);
DISPLAY 0.574468 (-6625 2825);
PAINT GREEN (-6625 2825);
DISPLAY INVISIBLE (-6625 2825);
FORCEPROP 1 LAST HDL_TAP TRUE
J 0
(-6300 2750);
DISPLAY 0.574468 (-6300 2750);
PAINT GREEN (-6300 2750);
DISPLAY INVISIBLE (-6300 2750);
FORCEPROP 1 LAST PATH I451
J 0
(-6627 2875);
DISPLAY 0.872340 (-6627 2875);
PAINT GREEN (-6627 2875);
DISPLAY INVISIBLE (-6627 2875);
FORCEADD TAP..6
(-6625 2775);
FORCEPROP 3 LASTPIN (-6575 2775) SIG_NAME GMI_CPU0_G1_CPU1_G3_TX_DN<12>
J 0
(-6565 2785);
DISPLAY 0.659574 (-6565 2785);
PAINT MONO (-6565 2785);
DISPLAY INVISIBLE (-6565 2785);
FORCEPROP 1 LASTPIN (-6575 2775) BN 12
J 0
(-6627 2783);
DISPLAY 0.489362 (-6627 2783);
PAINT MONO (-6627 2783);
FORCEPROP 2 LAST CDS_LIB standard
J 0
(-6625 2775);
DISPLAY INVISIBLE (-6625 2775);
FORCEPROP 1 LAST BODY_TYPE PLUMBING
J 0
(-6625 2725);
DISPLAY 0.574468 (-6625 2725);
PAINT GREEN (-6625 2725);
DISPLAY INVISIBLE (-6625 2725);
FORCEPROP 1 LAST HDL_TAP TRUE
J 0
(-6300 2650);
DISPLAY 0.574468 (-6300 2650);
PAINT GREEN (-6300 2650);
DISPLAY INVISIBLE (-6300 2650);
FORCEPROP 1 LAST PATH I452
J 0
(-6627 2775);
DISPLAY 0.872340 (-6627 2775);
PAINT GREEN (-6627 2775);
DISPLAY INVISIBLE (-6627 2775);
FORCEADD TAP..6
(-6625 2675);
FORCEPROP 3 LASTPIN (-6575 2675) SIG_NAME GMI_CPU0_G1_CPU1_G3_TX_DN<11>
J 0
(-6565 2685);
DISPLAY 0.659574 (-6565 2685);
PAINT MONO (-6565 2685);
DISPLAY INVISIBLE (-6565 2685);
FORCEPROP 1 LASTPIN (-6575 2675) BN 11
J 0
(-6627 2683);
DISPLAY 0.489362 (-6627 2683);
PAINT MONO (-6627 2683);
FORCEPROP 2 LAST CDS_LIB standard
J 0
(-6625 2675);
DISPLAY INVISIBLE (-6625 2675);
FORCEPROP 1 LAST BODY_TYPE PLUMBING
J 0
(-6625 2625);
DISPLAY 0.574468 (-6625 2625);
PAINT GREEN (-6625 2625);
DISPLAY INVISIBLE (-6625 2625);
FORCEPROP 1 LAST HDL_TAP TRUE
J 0
(-6300 2550);
DISPLAY 0.574468 (-6300 2550);
PAINT GREEN (-6300 2550);
DISPLAY INVISIBLE (-6300 2550);
FORCEPROP 1 LAST PATH I453
J 0
(-6627 2675);
DISPLAY 0.872340 (-6627 2675);
PAINT GREEN (-6627 2675);
DISPLAY INVISIBLE (-6627 2675);
FORCEADD TAP..6
(-6625 2475);
FORCEPROP 3 LASTPIN (-6575 2475) SIG_NAME GMI_CPU0_G1_CPU1_G3_TX_DN<9>
J 0
(-6565 2485);
DISPLAY 0.659574 (-6565 2485);
PAINT MONO (-6565 2485);
DISPLAY INVISIBLE (-6565 2485);
FORCEPROP 1 LASTPIN (-6575 2475) BN 9
J 0
(-6627 2483);
DISPLAY 0.489362 (-6627 2483);
PAINT MONO (-6627 2483);
FORCEPROP 2 LAST CDS_LIB standard
J 0
(-6625 2475);
DISPLAY INVISIBLE (-6625 2475);
FORCEPROP 1 LAST BODY_TYPE PLUMBING
J 0
(-6625 2425);
DISPLAY 0.574468 (-6625 2425);
PAINT GREEN (-6625 2425);
DISPLAY INVISIBLE (-6625 2425);
FORCEPROP 1 LAST HDL_TAP TRUE
J 0
(-6300 2350);
DISPLAY 0.574468 (-6300 2350);
PAINT GREEN (-6300 2350);
DISPLAY INVISIBLE (-6300 2350);
FORCEPROP 1 LAST PATH I454
J 0
(-6627 2475);
DISPLAY 0.872340 (-6627 2475);
PAINT GREEN (-6627 2475);
DISPLAY INVISIBLE (-6627 2475);
FORCEADD TAP..6
(-6625 2575);
FORCEPROP 3 LASTPIN (-6575 2575) SIG_NAME GMI_CPU0_G1_CPU1_G3_TX_DN<10>
J 0
(-6565 2585);
DISPLAY 0.659574 (-6565 2585);
PAINT MONO (-6565 2585);
DISPLAY INVISIBLE (-6565 2585);
FORCEPROP 1 LASTPIN (-6575 2575) BN 10
J 0
(-6627 2583);
DISPLAY 0.489362 (-6627 2583);
PAINT MONO (-6627 2583);
FORCEPROP 2 LAST CDS_LIB standard
J 0
(-6625 2575);
DISPLAY INVISIBLE (-6625 2575);
FORCEPROP 1 LAST BODY_TYPE PLUMBING
J 0
(-6625 2525);
DISPLAY 0.574468 (-6625 2525);
PAINT GREEN (-6625 2525);
DISPLAY INVISIBLE (-6625 2525);
FORCEPROP 1 LAST HDL_TAP TRUE
J 0
(-6300 2450);
DISPLAY 0.574468 (-6300 2450);
PAINT GREEN (-6300 2450);
DISPLAY INVISIBLE (-6300 2450);
FORCEPROP 1 LAST PATH I455
J 0
(-6627 2575);
DISPLAY 0.872340 (-6627 2575);
PAINT GREEN (-6627 2575);
DISPLAY INVISIBLE (-6627 2575);
FORCEADD TAP..6
(-6625 2375);
FORCEPROP 3 LASTPIN (-6575 2375) SIG_NAME GMI_CPU0_G1_CPU1_G3_TX_DN<8>
J 0
(-6565 2385);
DISPLAY 0.659574 (-6565 2385);
PAINT MONO (-6565 2385);
DISPLAY INVISIBLE (-6565 2385);
FORCEPROP 1 LASTPIN (-6575 2375) BN 8
J 0
(-6627 2383);
DISPLAY 0.489362 (-6627 2383);
PAINT MONO (-6627 2383);
FORCEPROP 2 LAST CDS_LIB standard
J 0
(-6625 2375);
DISPLAY INVISIBLE (-6625 2375);
FORCEPROP 1 LAST BODY_TYPE PLUMBING
J 0
(-6625 2325);
DISPLAY 0.574468 (-6625 2325);
PAINT GREEN (-6625 2325);
DISPLAY INVISIBLE (-6625 2325);
FORCEPROP 1 LAST HDL_TAP TRUE
J 0
(-6300 2250);
DISPLAY 0.574468 (-6300 2250);
PAINT GREEN (-6300 2250);
DISPLAY INVISIBLE (-6300 2250);
FORCEPROP 1 LAST PATH I456
J 0
(-6627 2375);
DISPLAY 0.872340 (-6627 2375);
PAINT GREEN (-6627 2375);
DISPLAY INVISIBLE (-6627 2375);
FORCEADD TAP..6
(-6625 2275);
FORCEPROP 3 LASTPIN (-6575 2275) SIG_NAME GMI_CPU0_G1_CPU1_G3_TX_DN<7>
J 0
(-6565 2285);
DISPLAY 0.659574 (-6565 2285);
PAINT MONO (-6565 2285);
DISPLAY INVISIBLE (-6565 2285);
FORCEPROP 1 LASTPIN (-6575 2275) BN 7
J 0
(-6627 2283);
DISPLAY 0.489362 (-6627 2283);
PAINT MONO (-6627 2283);
FORCEPROP 2 LAST CDS_LIB standard
J 0
(-6625 2275);
DISPLAY INVISIBLE (-6625 2275);
FORCEPROP 1 LAST BODY_TYPE PLUMBING
J 0
(-6625 2225);
DISPLAY 0.574468 (-6625 2225);
PAINT GREEN (-6625 2225);
DISPLAY INVISIBLE (-6625 2225);
FORCEPROP 1 LAST HDL_TAP TRUE
J 0
(-6300 2150);
DISPLAY 0.574468 (-6300 2150);
PAINT GREEN (-6300 2150);
DISPLAY INVISIBLE (-6300 2150);
FORCEPROP 1 LAST PATH I457
J 0
(-6627 2275);
DISPLAY 0.872340 (-6627 2275);
PAINT GREEN (-6627 2275);
DISPLAY INVISIBLE (-6627 2275);
FORCEADD TAP..6
(-6625 2175);
FORCEPROP 3 LASTPIN (-6575 2175) SIG_NAME GMI_CPU0_G1_CPU1_G3_TX_DN<6>
J 0
(-6565 2185);
DISPLAY 0.659574 (-6565 2185);
PAINT MONO (-6565 2185);
DISPLAY INVISIBLE (-6565 2185);
FORCEPROP 1 LASTPIN (-6575 2175) BN 6
J 0
(-6627 2183);
DISPLAY 0.489362 (-6627 2183);
PAINT MONO (-6627 2183);
FORCEPROP 2 LAST CDS_LIB standard
J 0
(-6625 2175);
DISPLAY INVISIBLE (-6625 2175);
FORCEPROP 1 LAST BODY_TYPE PLUMBING
J 0
(-6625 2125);
DISPLAY 0.574468 (-6625 2125);
PAINT GREEN (-6625 2125);
DISPLAY INVISIBLE (-6625 2125);
FORCEPROP 1 LAST HDL_TAP TRUE
J 0
(-6300 2050);
DISPLAY 0.574468 (-6300 2050);
PAINT GREEN (-6300 2050);
DISPLAY INVISIBLE (-6300 2050);
FORCEPROP 1 LAST PATH I458
J 0
(-6627 2175);
DISPLAY 0.872340 (-6627 2175);
PAINT GREEN (-6627 2175);
DISPLAY INVISIBLE (-6627 2175);
FORCEADD TAP..6
(-6625 1975);
FORCEPROP 3 LASTPIN (-6575 1975) SIG_NAME GMI_CPU0_G1_CPU1_G3_TX_DN<4>
J 0
(-6565 1985);
DISPLAY 0.659574 (-6565 1985);
PAINT MONO (-6565 1985);
DISPLAY INVISIBLE (-6565 1985);
FORCEPROP 1 LASTPIN (-6575 1975) BN 4
J 0
(-6627 1983);
DISPLAY 0.489362 (-6627 1983);
PAINT MONO (-6627 1983);
FORCEPROP 2 LAST CDS_LIB standard
J 0
(-6625 1975);
DISPLAY INVISIBLE (-6625 1975);
FORCEPROP 1 LAST BODY_TYPE PLUMBING
J 0
(-6625 1925);
DISPLAY 0.574468 (-6625 1925);
PAINT GREEN (-6625 1925);
DISPLAY INVISIBLE (-6625 1925);
FORCEPROP 1 LAST HDL_TAP TRUE
J 0
(-6300 1850);
DISPLAY 0.574468 (-6300 1850);
PAINT GREEN (-6300 1850);
DISPLAY INVISIBLE (-6300 1850);
FORCEPROP 1 LAST PATH I459
J 0
(-6627 1975);
DISPLAY 0.872340 (-6627 1975);
PAINT GREEN (-6627 1975);
DISPLAY INVISIBLE (-6627 1975);
FORCEADD TAP..6
(-6625 2075);
FORCEPROP 3 LASTPIN (-6575 2075) SIG_NAME GMI_CPU0_G1_CPU1_G3_TX_DN<5>
J 0
(-6565 2085);
DISPLAY 0.659574 (-6565 2085);
PAINT MONO (-6565 2085);
DISPLAY INVISIBLE (-6565 2085);
FORCEPROP 1 LASTPIN (-6575 2075) BN 5
J 0
(-6627 2083);
DISPLAY 0.489362 (-6627 2083);
PAINT MONO (-6627 2083);
FORCEPROP 2 LAST CDS_LIB standard
J 0
(-6625 2075);
DISPLAY INVISIBLE (-6625 2075);
FORCEPROP 1 LAST BODY_TYPE PLUMBING
J 0
(-6625 2025);
DISPLAY 0.574468 (-6625 2025);
PAINT GREEN (-6625 2025);
DISPLAY INVISIBLE (-6625 2025);
FORCEPROP 1 LAST HDL_TAP TRUE
J 0
(-6300 1950);
DISPLAY 0.574468 (-6300 1950);
PAINT GREEN (-6300 1950);
DISPLAY INVISIBLE (-6300 1950);
FORCEPROP 1 LAST PATH I460
J 0
(-6627 2075);
DISPLAY 0.872340 (-6627 2075);
PAINT GREEN (-6627 2075);
DISPLAY INVISIBLE (-6627 2075);
FORCEADD TAP..6
(-6625 1875);
FORCEPROP 3 LASTPIN (-6575 1875) SIG_NAME GMI_CPU0_G1_CPU1_G3_TX_DN<3>
J 0
(-6565 1885);
DISPLAY 0.659574 (-6565 1885);
PAINT MONO (-6565 1885);
DISPLAY INVISIBLE (-6565 1885);
FORCEPROP 1 LASTPIN (-6575 1875) BN 3
J 0
(-6627 1883);
DISPLAY 0.489362 (-6627 1883);
PAINT MONO (-6627 1883);
FORCEPROP 2 LAST CDS_LIB standard
J 0
(-6625 1875);
DISPLAY INVISIBLE (-6625 1875);
FORCEPROP 1 LAST BODY_TYPE PLUMBING
J 0
(-6625 1825);
DISPLAY 0.574468 (-6625 1825);
PAINT GREEN (-6625 1825);
DISPLAY INVISIBLE (-6625 1825);
FORCEPROP 1 LAST HDL_TAP TRUE
J 0
(-6300 1750);
DISPLAY 0.574468 (-6300 1750);
PAINT GREEN (-6300 1750);
DISPLAY INVISIBLE (-6300 1750);
FORCEPROP 1 LAST PATH I461
J 0
(-6627 1875);
DISPLAY 0.872340 (-6627 1875);
PAINT GREEN (-6627 1875);
DISPLAY INVISIBLE (-6627 1875);
FORCEADD TAP..6
(-6625 1775);
FORCEPROP 3 LASTPIN (-6575 1775) SIG_NAME GMI_CPU0_G1_CPU1_G3_TX_DN<2>
J 0
(-6565 1785);
DISPLAY 0.659574 (-6565 1785);
PAINT MONO (-6565 1785);
DISPLAY INVISIBLE (-6565 1785);
FORCEPROP 1 LASTPIN (-6575 1775) BN 2
J 0
(-6627 1783);
DISPLAY 0.489362 (-6627 1783);
PAINT MONO (-6627 1783);
FORCEPROP 2 LAST CDS_LIB standard
J 0
(-6625 1775);
DISPLAY INVISIBLE (-6625 1775);
FORCEPROP 1 LAST BODY_TYPE PLUMBING
J 0
(-6625 1725);
DISPLAY 0.574468 (-6625 1725);
PAINT GREEN (-6625 1725);
DISPLAY INVISIBLE (-6625 1725);
FORCEPROP 1 LAST HDL_TAP TRUE
J 0
(-6300 1650);
DISPLAY 0.574468 (-6300 1650);
PAINT GREEN (-6300 1650);
DISPLAY INVISIBLE (-6300 1650);
FORCEPROP 1 LAST PATH I462
J 0
(-6627 1775);
DISPLAY 0.872340 (-6627 1775);
PAINT GREEN (-6627 1775);
DISPLAY INVISIBLE (-6627 1775);
FORCEADD TAP..6
(-6625 1575);
FORCEPROP 3 LASTPIN (-6575 1575) SIG_NAME GMI_CPU0_G1_CPU1_G3_TX_DN<0>
J 0
(-6565 1585);
DISPLAY 0.659574 (-6565 1585);
PAINT MONO (-6565 1585);
DISPLAY INVISIBLE (-6565 1585);
FORCEPROP 1 LASTPIN (-6575 1575) BN 0
J 0
(-6627 1583);
DISPLAY 0.489362 (-6627 1583);
PAINT MONO (-6627 1583);
FORCEPROP 2 LAST CDS_LIB standard
J 0
(-6625 1575);
DISPLAY INVISIBLE (-6625 1575);
FORCEPROP 1 LAST BODY_TYPE PLUMBING
J 0
(-6625 1525);
DISPLAY 0.574468 (-6625 1525);
PAINT GREEN (-6625 1525);
DISPLAY INVISIBLE (-6625 1525);
FORCEPROP 1 LAST HDL_TAP TRUE
J 0
(-6300 1450);
DISPLAY 0.574468 (-6300 1450);
PAINT GREEN (-6300 1450);
DISPLAY INVISIBLE (-6300 1450);
FORCEPROP 1 LAST PATH I463
J 0
(-6627 1575);
DISPLAY 0.872340 (-6627 1575);
PAINT GREEN (-6627 1575);
DISPLAY INVISIBLE (-6627 1575);
FORCEADD TAP..6
(-6625 1675);
FORCEPROP 3 LASTPIN (-6575 1675) SIG_NAME GMI_CPU0_G1_CPU1_G3_TX_DN<1>
J 0
(-6565 1685);
DISPLAY 0.659574 (-6565 1685);
PAINT MONO (-6565 1685);
DISPLAY INVISIBLE (-6565 1685);
FORCEPROP 1 LASTPIN (-6575 1675) BN 1
J 0
(-6627 1683);
DISPLAY 0.489362 (-6627 1683);
PAINT MONO (-6627 1683);
FORCEPROP 2 LAST CDS_LIB standard
J 0
(-6625 1675);
DISPLAY INVISIBLE (-6625 1675);
FORCEPROP 1 LAST BODY_TYPE PLUMBING
J 0
(-6625 1625);
DISPLAY 0.574468 (-6625 1625);
PAINT GREEN (-6625 1625);
DISPLAY INVISIBLE (-6625 1625);
FORCEPROP 1 LAST HDL_TAP TRUE
J 0
(-6300 1550);
DISPLAY 0.574468 (-6300 1550);
PAINT GREEN (-6300 1550);
DISPLAY INVISIBLE (-6300 1550);
FORCEPROP 1 LAST PATH I464
J 0
(-6627 1675);
DISPLAY 0.872340 (-6627 1675);
PAINT GREEN (-6627 1675);
DISPLAY INVISIBLE (-6627 1675);
FORCEADD OFFPAGE..1
(-7575 3300);
FORCEPROP 2 LASTPIN (-7525 3300) SIG_NAME GMI_CPU0_G1_CPU1_G3_TX_DN<15:0>
J 0
(-7535 3310);
DISPLAY 0.489362 (-7535 3310);
FORCEPROP 2 LAST $XR0 22 
J 0
(-7826 3300);
DISPLAY 0.638298 (-7826 3300);
PAINT MONO (-7826 3300);
FORCEPROP 2 LAST CDS_LIB standard
J 0
(-7575 3300);
DISPLAY INVISIBLE (-7575 3300);
FORCEPROP 1 LAST OFFPAGE TRUE
J 0
(-7250 3175);
DISPLAY 0.872340 (-7250 3175);
PAINT GREEN (-7250 3175);
DISPLAY INVISIBLE (-7250 3175);
FORCEPROP 1 LAST COMMENT_BODY TRUE
J 0
(-7450 3200);
DISPLAY 0.872340 (-7450 3200);
PAINT GREEN (-7450 3200);
DISPLAY INVISIBLE (-7450 3200);
FORCEPROP 2 LAST PATH I465
J 0
(-7825 3350);
DISPLAY 1.021277 (-7825 3350);
DISPLAY INVISIBLE (-7825 3350);
FORCEADD QUANTA_TITLE_BLOCK_C..1
(-100 100);
FORCEPROP 0 LAST CDS_CON_LAST_MODIFIED Thu Sep 14 16:11:59 2023
J 0
(-1985 115);
DISPLAY INVISIBLE (-1985 115);
FORCEPROP 1 LAST CUSTOM_TXT_CDS <CON_LAST_MODIFIED>
J 0
(-1985 115);
DISPLAY 0.978723 (-1985 115);
FORCEPROP 2 LAST CUSTOM_TXT_CDS <XR_PAGE_TITLE>
J 0
(-7990 5350);
DISPLAY 0.638298 (-7990 5350);
PAINT PINK (-7990 5350);
DISPLAY INVISIBLE (-7990 5350);
FORCEPROP 1 LAST CUSTOM_TXT_CDS <NAME_2>
J 0
(-3275 150);
FORCEPROP 1 LAST CUSTOM_TXT_CDS <NAME_1>
J 0
(-3275 275);
FORCEPROP 1 LAST CUSTOM_TXT_CDS <Q_NUMBER>
J 0
(-1503 203);
DISPLAY 1.212766 (-1503 203);
FORCEPROP 1 LAST CUSTOM_TXT_CDS <Q_PROJ>
J 0
(-2482 202);
DISPLAY 1.212766 (-2482 202);
FORCEPROP 1 LAST CUSTOM_TXT_CDS <Q_REV>
J 0
(-284 203);
DISPLAY 1.212766 (-284 203);
FORCEPROP 1 LAST CUSTOM_TXT_CDS <CON_PAGE_NUM> OF <CON_TOTAL_PAGES>
J 0
(-546 118);
DISPLAY 0.978723 (-546 118);
FORCEPROP 1 LAST Q_TITLE CPU1 PCIE G2/G3
J 0
(-9466 126);
DISPLAY 2.446809 (-9466 126);
PAINT GREEN (-9466 126);
FORCEPROP 2 LAST PAGE_BORDER TRUE
J 0
(-7990 5350);
DISPLAY 0.638298 (-7990 5350);
PAINT PINK (-7990 5350);
DISPLAY INVISIBLE (-7990 5350);
FORCEPROP 1 LAST CDS_LMAN_SYM_OUTLINE -9475,6775,100,-125
J 0
(-100 100);
DISPLAY 0.468085 (-100 100);
PAINT GREEN (-100 100);
DISPLAY INVISIBLE (-100 100);
FORCEPROP 2 LAST CDS_LIB pure_quanta
J 0
(-100 100);
DISPLAY INVISIBLE (-100 100);
FORCEPROP 2 LAST CDS_XR_PAGE_TITLE CR-50 : @T6G_MB_LIB.T6G(SCH_1):PAGE50
J 0
(-7990 5350);
DISPLAY 0.638298 (-7990 5350);
PAINT PINK (-7990 5350);
DISPLAY INVISIBLE (-7990 5350);
FORCEPROP 1 LAST Q_DEPT BU9
J 1
(-3863 149);
DISPLAY 1.957447 (-3863 149);
PAINT GREEN (-3863 149);
DISPLAY INVISIBLE (-3863 149);
FORCEPROP 1 LAST COMMENT_BODY TRUE
J 0
(-88 87);
DISPLAY 0.978723 (-88 87);
PAINT GREEN (-88 87);
DISPLAY INVISIBLE (-88 87);
WIRE 17 -1 (-2875 5075)(-2875 4975);
WIRE 17 -1 (-2875 5175)(-2875 5075);
WIRE 17 -1 (-2875 4975)(-2875 4875);
WIRE 17 -1 (-2875 4875)(-2875 4775);
WIRE 17 -1 (-2875 5275)(-2875 5175);
WIRE 17 -1 (-2875 5375)(-2875 5275);
WIRE 17 -1 (-2875 4775)(-2875 4675);
WIRE 17 -1 (-2875 4675)(-2875 4575);
WIRE 17 -1 (-2875 5475)(-2875 5375);
WIRE 17 -1 (-2875 5575)(-2875 5475);
WIRE 17 -1 (-2875 4575)(-2875 4475);
WIRE 17 -1 (-2875 4475)(-2875 4375);
WIRE 17 -1 (-2875 5675)(-2875 5575);
WIRE 17 -1 (-2875 5775)(-2875 5675);
WIRE 17 -1 (-2875 4375)(-2875 4275);
WIRE 17 -1 (-2875 5975)(-2875 5775);
WIRE 17 -1 (-2875 5975)(-1850 5975);
FORCEPROP 2 LAST SIG_NAME GMI_CPU1_G2_CPU0_G0_TX_DN<15:0>
J 0
(-2835 5985);
DISPLAY 0.489362 (-2835 5985);
WIRE 17 -1 (-3025 5825)(-3025 5725);
WIRE 17 -1 (-3025 6025)(-3025 5825);
WIRE 17 -1 (-3025 5725)(-3025 5625);
WIRE 17 -1 (-3025 5625)(-3025 5525);
WIRE 17 -1 (-3025 6025)(-1850 6025);
FORCEPROP 2 LAST SIG_NAME GMI_CPU1_G2_CPU0_G0_TX_DP<15:0>
J 0
(-2835 6035);
DISPLAY 0.489362 (-2835 6035);
WIRE 17 -1 (-3025 5525)(-3025 5425);
WIRE 17 -1 (-3025 5425)(-3025 5325);
WIRE 17 -1 (-3025 5325)(-3025 5225);
WIRE 17 -1 (-3025 5225)(-3025 5125);
WIRE 17 -1 (-3025 5125)(-3025 5025);
WIRE 17 -1 (-3025 5025)(-3025 4925);
WIRE 17 -1 (-3025 4925)(-3025 4825);
WIRE 17 -1 (-3025 4825)(-3025 4725);
WIRE 17 -1 (-3025 4725)(-3025 4625);
WIRE 17 -1 (-3025 4625)(-3025 4525);
WIRE 17 -1 (-3025 4525)(-3025 4425);
WIRE 17 -1 (-3025 4425)(-3025 4325);
WIRE 17 -1 (-2850 3000)(-2850 2900);
WIRE 17 -1 (-2850 3100)(-2850 3000);
WIRE 17 -1 (-2850 2900)(-2850 2800);
WIRE 17 -1 (-2850 2800)(-2850 2700);
WIRE 17 -1 (-2850 3300)(-2850 3100);
WIRE 17 -1 (-2850 3300)(-1825 3300);
FORCEPROP 2 LAST SIG_NAME GMI_CPU1_G3_CPU0_G1_TX_DN<15:0>
J 0
(-2760 3310);
DISPLAY 0.489362 (-2760 3310);
WIRE 17 -1 (-2850 2700)(-2850 2600);
WIRE 17 -1 (-2850 2600)(-2850 2500);
WIRE 17 -1 (-2850 2500)(-2850 2400);
WIRE 17 -1 (-2850 2400)(-2850 2300);
WIRE 17 -1 (-2850 2300)(-2850 2200);
WIRE 17 -1 (-2850 2200)(-2850 2100);
WIRE 17 -1 (-2850 2100)(-2850 2000);
WIRE 17 -1 (-2850 2000)(-2850 1900);
WIRE 17 -1 (-2850 1900)(-2850 1800);
WIRE 17 -1 (-2850 1800)(-2850 1700);
WIRE 17 -1 (-2850 1700)(-2850 1600);
WIRE 17 -1 (-3000 3350)(-3000 3150);
WIRE 17 -1 (-3000 3350)(-1825 3350);
FORCEPROP 2 LAST SIG_NAME GMI_CPU1_G3_CPU0_G1_TX_DP<15:0>
J 0
(-2760 3360);
DISPLAY 0.489362 (-2760 3360);
WIRE 17 -1 (-3000 2950)(-3000 2850);
WIRE 17 -1 (-3000 3050)(-3000 2950);
WIRE 17 -1 (-3000 2850)(-3000 2750);
WIRE 17 -1 (-3000 2750)(-3000 2650);
WIRE 17 -1 (-3000 3150)(-3000 3050);
WIRE 17 -1 (-3000 2650)(-3000 2550);
WIRE 17 -1 (-3000 2550)(-3000 2450);
WIRE 17 -1 (-3000 2450)(-3000 2350);
WIRE 17 -1 (-3000 2350)(-3000 2250);
WIRE 17 -1 (-3000 2250)(-3000 2150);
WIRE 17 -1 (-3000 2150)(-3000 2050);
WIRE 17 -1 (-3000 2050)(-3000 1950);
WIRE 17 -1 (-3000 1950)(-3000 1850);
WIRE 17 -1 (-3000 1850)(-3000 1750);
WIRE 17 -1 (-3000 1750)(-3000 1650);
WIRE 17 -1 (-6550 4925)(-6550 5025);
WIRE 17 -1 (-6550 4825)(-6550 4925);
WIRE 17 -1 (-6550 5025)(-6550 5125);
WIRE 17 -1 (-6550 5125)(-6550 5225);
WIRE 17 -1 (-6550 4725)(-6550 4825);
WIRE 17 -1 (-6550 4625)(-6550 4725);
WIRE 17 -1 (-6550 5225)(-6550 5325);
WIRE 17 -1 (-6550 5325)(-6550 5425);
WIRE 17 -1 (-6550 4525)(-6550 4625);
WIRE 17 -1 (-6550 4425)(-6550 4525);
WIRE 17 -1 (-6550 5425)(-6550 5525);
WIRE 17 -1 (-6550 5525)(-6550 5625);
WIRE 17 -1 (-6550 4325)(-6550 4425);
WIRE 17 -1 (-6550 5625)(-6550 5725);
WIRE 17 -1 (-6550 5725)(-6550 5825);
WIRE 17 -1 (-6550 5825)(-6550 6025);
WIRE 17 -1 (-6550 6025)(-7650 6025);
FORCEPROP 2 LAST SIG_NAME GMI_CPU0_G0_CPU1_G2_TX_DP<15:0>
J 0
(-7610 6035);
DISPLAY 0.489362 (-7610 6035);
WIRE 17 -1 (-6700 4875)(-6700 4975);
WIRE 17 -1 (-6700 4775)(-6700 4875);
WIRE 17 -1 (-6700 4975)(-6700 5075);
WIRE 17 -1 (-6700 5075)(-6700 5175);
WIRE 17 -1 (-6700 4675)(-6700 4775);
WIRE 17 -1 (-6700 4575)(-6700 4675);
WIRE 17 -1 (-6700 5175)(-6700 5275);
WIRE 17 -1 (-6700 5275)(-6700 5375);
WIRE 17 -1 (-6700 4475)(-6700 4575);
WIRE 17 -1 (-6700 4375)(-6700 4475);
WIRE 17 -1 (-6700 5375)(-6700 5475);
WIRE 17 -1 (-6700 5475)(-6700 5575);
WIRE 17 -1 (-6700 4275)(-6700 4375);
WIRE 17 -1 (-6700 5575)(-6700 5675);
WIRE 17 -1 (-6700 5675)(-6700 5775);
WIRE 17 -1 (-6700 5775)(-6700 5975);
WIRE 17 -1 (-6700 5975)(-7650 5975);
FORCEPROP 2 LAST SIG_NAME GMI_CPU0_G0_CPU1_G2_TX_DN<15:0>
J 0
(-7610 5985);
DISPLAY 0.489362 (-7610 5985);
WIRE 17 -1 (-6675 2700)(-6675 2600);
WIRE 17 -1 (-6675 2800)(-6675 2700);
WIRE 17 -1 (-6675 2600)(-6675 2500);
WIRE 17 -1 (-6675 2500)(-6675 2400);
WIRE 17 -1 (-6675 2900)(-6675 2800);
WIRE 17 -1 (-6675 3000)(-6675 2900);
WIRE 17 -1 (-6675 2400)(-6675 2300);
WIRE 17 -1 (-6675 2300)(-6675 2200);
WIRE 17 -1 (-6675 3100)(-6675 3000);
WIRE 17 -1 (-6675 3300)(-6675 3100);
WIRE 17 -1 (-6675 2200)(-6675 2100);
WIRE 17 -1 (-6675 2100)(-6675 2000);
WIRE 17 -1 (-6675 3300)(-7525 3300);
WIRE 17 -1 (-6525 2050)(-6525 1950);
WIRE 17 -1 (-6525 2150)(-6525 2050);
WIRE 17 -1 (-6525 1950)(-6525 1850);
WIRE 17 -1 (-6525 1850)(-6525 1750);
WIRE 17 -1 (-6525 2250)(-6525 2150);
WIRE 17 -1 (-6525 2350)(-6525 2250);
WIRE 17 -1 (-6525 1750)(-6525 1650);
WIRE 17 -1 (-6525 2450)(-6525 2350);
WIRE 17 -1 (-6525 2550)(-6525 2450);
WIRE 17 -1 (-6525 2650)(-6525 2550);
WIRE 17 -1 (-6525 2750)(-6525 2650);
WIRE 17 -1 (-6525 2850)(-6525 2750);
WIRE 17 -1 (-6525 2950)(-6525 2850);
WIRE 17 -1 (-6525 3050)(-6525 2950);
WIRE 17 -1 (-6525 3150)(-6525 3050);
WIRE 17 -1 (-6525 3350)(-6525 3150);
WIRE 17 -1 (-6525 3350)(-7525 3350);
WIRE 17 -1 (-6675 2000)(-6675 1900);
WIRE 17 -1 (-6675 1900)(-6675 1800);
WIRE 17 -1 (-6675 1800)(-6675 1700);
WIRE 17 -1 (-6675 1700)(-6675 1600);
WIRE 16 -1 (-6575 2875)(-5975 2875);
WIRE 16 -1 (-6575 1875)(-5975 1875);
WIRE 16 -1 (-6575 1575)(-5975 1575);
WIRE 16 -1 (-6575 2175)(-5975 2175);
WIRE 16 -1 (-6425 2925)(-5975 2925);
WIRE 16 -1 (-6425 2625)(-5975 2625);
WIRE 16 -1 (-6425 1725)(-5975 1725);
WIRE 16 -1 (-6425 2025)(-5975 2025);
WIRE 16 -1 (-6575 2975)(-5975 2975);
WIRE 16 -1 (-6575 2675)(-5975 2675);
WIRE 16 -1 (-6575 2375)(-5975 2375);
WIRE 16 -1 (-6425 2225)(-5975 2225);
WIRE 16 -1 (-6575 1975)(-5975 1975);
WIRE 16 -1 (-6575 1675)(-5975 1675);
WIRE 16 -1 (-6425 2425)(-5975 2425);
WIRE 16 -1 (-6575 2275)(-5975 2275);
WIRE 16 -1 (-6425 3025)(-5975 3025);
WIRE 16 -1 (-6425 2725)(-5975 2725);
WIRE 16 -1 (-6425 2125)(-5975 2125);
WIRE 16 -1 (-6425 1825)(-5975 1825);
WIRE 16 -1 (-6575 2475)(-5975 2475);
WIRE 16 -1 (-6575 3075)(-5975 3075);
WIRE 16 -1 (-6575 2775)(-5975 2775);
WIRE 16 -1 (-6425 2325)(-5975 2325);
WIRE 16 -1 (-6575 1775)(-5975 1775);
WIRE 16 -1 (-6575 2075)(-5975 2075);
WIRE 16 -1 (-6425 2825)(-5975 2825);
WIRE 16 -1 (-6425 2525)(-5975 2525);
WIRE 16 -1 (-6425 1625)(-5975 1625);
WIRE 16 -1 (-6425 3125)(-5975 3125);
WIRE 16 -1 (-6425 1925)(-5975 1925);
WIRE 16 -1 (-6575 2575)(-5975 2575);
WIRE 16 -1 (-6600 5050)(-6000 5050);
WIRE 16 -1 (-6600 5150)(-6000 5150);
WIRE 16 -1 (-6600 5250)(-6000 5250);
WIRE 16 -1 (-6450 5100)(-6000 5100);
WIRE 16 -1 (-6600 5350)(-6000 5350);
WIRE 16 -1 (-6450 5200)(-6000 5200);
WIRE 16 -1 (-6600 5450)(-6000 5450);
WIRE 16 -1 (-6450 5300)(-6000 5300);
WIRE 16 -1 (-6600 5550)(-6000 5550);
WIRE 16 -1 (-6450 5400)(-6000 5400);
WIRE 16 -1 (-6600 5650)(-6000 5650);
WIRE 16 -1 (-6450 5500)(-6000 5500);
WIRE 16 -1 (-6600 5750)(-6000 5750);
WIRE 16 -1 (-6450 5600)(-6000 5600);
WIRE 16 -1 (-6450 5700)(-6000 5700);
WIRE 16 -1 (-6450 5800)(-6000 5800);
WIRE 16 -1 (-6600 4250)(-6000 4250);
WIRE 16 -1 (-6450 4300)(-6000 4300);
WIRE 16 -1 (-6600 4450)(-6000 4450);
WIRE 16 -1 (-6450 4500)(-6000 4500);
WIRE 16 -1 (-6600 4650)(-6000 4650);
WIRE 16 -1 (-6450 4700)(-6000 4700);
WIRE 16 -1 (-6600 4850)(-6000 4850);
WIRE 16 -1 (-6450 4900)(-6000 4900);
WIRE 16 -1 (-6600 4350)(-6000 4350);
WIRE 16 -1 (-6450 4400)(-6000 4400);
WIRE 16 -1 (-6600 4550)(-6000 4550);
WIRE 16 -1 (-6450 4600)(-6000 4600);
WIRE 16 -1 (-6600 4750)(-6000 4750);
WIRE 16 -1 (-6450 4800)(-6000 4800);
WIRE 16 -1 (-6600 4950)(-6000 4950);
WIRE 16 -1 (-6450 5000)(-6000 5000);
WIRE 16 -1 (-3475 1625)(-3100 1625);
WIRE 16 -1 (-3475 1925)(-3100 1925);
WIRE 16 -1 (-3475 1725)(-3100 1725);
WIRE 16 -1 (-3475 2025)(-3100 2025);
WIRE 16 -1 (-3475 1825)(-3100 1825);
WIRE 16 -1 (-3475 1775)(-2950 1775);
WIRE 16 -1 (-3475 1875)(-2950 1875);
WIRE 16 -1 (-3475 1575)(-2950 1575);
WIRE 16 -1 (-3475 1975)(-2950 1975);
WIRE 16 -1 (-3475 1675)(-2950 1675);
WIRE 16 -1 (-3475 2225)(-3100 2225);
WIRE 16 -1 (-3475 2425)(-3100 2425);
WIRE 16 -1 (-3475 2325)(-3100 2325);
WIRE 16 -1 (-3475 2525)(-3100 2525);
WIRE 16 -1 (-3475 2125)(-3100 2125);
WIRE 16 -1 (-3475 2625)(-3100 2625);
WIRE 16 -1 (-3475 2925)(-3100 2925);
WIRE 16 -1 (-3475 3025)(-3100 3025);
WIRE 16 -1 (-3475 2725)(-3100 2725);
WIRE 16 -1 (-3475 2825)(-3100 2825);
WIRE 16 -1 (-3475 3125)(-3100 3125);
WIRE 16 -1 (-3475 2175)(-2950 2175);
WIRE 16 -1 (-3475 2675)(-2950 2675);
WIRE 16 -1 (-3475 2375)(-2950 2375);
WIRE 16 -1 (-3475 2075)(-2950 2075);
WIRE 16 -1 (-3475 2975)(-2950 2975);
WIRE 16 -1 (-3475 2275)(-2950 2275);
WIRE 16 -1 (-3475 2775)(-2950 2775);
WIRE 16 -1 (-3475 2475)(-2950 2475);
WIRE 16 -1 (-3475 3075)(-2950 3075);
WIRE 16 -1 (-3475 2575)(-2950 2575);
WIRE 16 -1 (-3475 2875)(-2950 2875);
WIRE 16 -1 (-3500 4300)(-3125 4300);
WIRE 16 -1 (-3500 4500)(-3125 4500);
WIRE 16 -1 (-3500 4400)(-3125 4400);
WIRE 16 -1 (-3500 4600)(-3125 4600);
WIRE 16 -1 (-3500 5100)(-3125 5100);
WIRE 16 -1 (-3500 4700)(-3125 4700);
WIRE 16 -1 (-3500 4900)(-3125 4900);
WIRE 16 -1 (-3500 4800)(-3125 4800);
WIRE 16 -1 (-3500 5000)(-3125 5000);
WIRE 16 -1 (-3500 5200)(-3125 5200);
WIRE 16 -1 (-3500 5300)(-3125 5300);
WIRE 16 -1 (-3500 5400)(-3125 5400);
WIRE 16 -1 (-3500 5500)(-3125 5500);
WIRE 16 -1 (-3500 5600)(-3125 5600);
WIRE 16 -1 (-3500 5800)(-3125 5800);
WIRE 16 -1 (-3500 5700)(-3125 5700);
WIRE 16 -1 (-3500 5050)(-2975 5050);
WIRE 16 -1 (-3500 5150)(-2975 5150);
WIRE 16 -1 (-3500 5250)(-2975 5250);
WIRE 16 -1 (-3500 5350)(-2975 5350);
WIRE 16 -1 (-3500 5450)(-2975 5450);
WIRE 16 -1 (-3500 5550)(-2975 5550);
WIRE 16 -1 (-3500 5650)(-2975 5650);
WIRE 16 -1 (-3500 5750)(-2975 5750);
WIRE 16 -1 (-3500 4250)(-2975 4250);
WIRE 16 -1 (-3500 4450)(-2975 4450);
WIRE 16 -1 (-3500 4650)(-2975 4650);
WIRE 16 -1 (-3500 4850)(-2975 4850);
WIRE 16 -1 (-3500 4350)(-2975 4350);
WIRE 16 -1 (-3500 4550)(-2975 4550);
WIRE 16 -1 (-3500 4750)(-2975 4750);
WIRE 16 -1 (-3500 4950)(-2975 4950);
FORCENOTE
LANE REVERSAL
(-1925 2025) 0;
DISPLAY LEFT (-1925 2025);
DISPLAY 1.595745 (-1925 2025);
FORCENOTE
LANE REVERSAL
(-1900 4750) 0;
DISPLAY LEFT (-1900 4750);
DISPLAY 1.595745 (-1900 4750);
QUIT
